FILE_TYPE = MACRO_DRAWING;
SET COLOR_WIRE YELLOW;
SET COLOR_PROP ORANGE;
SET COLOR_DOT WHITE;
SET COLOR_ARC YELLOW;
SET COLOR_BODY GREEN;
SET COLOR_NOTE PURPLE;
SET PROP_DISPLAY VALUE;
SET PAGE_NUMBER P177;
FORCEADD UNIVERSAL_GND..1
(1300 875);
FORCEPROP 3 LASTPIN (1300 925) SIG_NAME GND\g
J 0
(1310 935);
DISPLAY 0.659574 (1310 935);
PAINT MONO (1310 935);
DISPLAY INVISIBLE (1310 935);
FORCEPROP 1 LAST HDL_POWER GND
J 1
(1325 800);
DISPLAY 0.872340 (1325 800);
PAINT GREEN (1325 800);
DISPLAY INVISIBLE (1325 800);
FORCEPROP 1 LAST PATH I1
J 0
(1375 875);
DISPLAY 0.872340 (1375 875);
PAINT AQUA (1375 875);
DISPLAY INVISIBLE (1375 875);
FORCEPROP 2 LAST CDS_LIB pure_quanta_power
J 0
(1300 875);
PAINT MONO (1300 875);
DISPLAY INVISIBLE (1300 875);
FORCEADD Q_CAP..1
(800 1225);
FORCEPROP 1 LAST LOCATION PC113_4
J 0
(850 1325);
DISPLAY 0.489362 (850 1325);
PAINT SKYBLUE (850 1325);
FORCEPROP 0 LAST $SEC 1
J 0
(850 1350);
DISPLAY 0.680851 (850 1350);
PAINT MONO (850 1350);
DISPLAY INVISIBLE (850 1350);
FORCEPROP 0 LAST CDS_SEC 1
J 0
(1050 1275);
DISPLAY 1.021277 (1050 1275);
DISPLAY INVISIBLE (1050 1275);
FORCEPROP 1 LASTPIN (800 1325) $PN 1
J 0
(810 1305);
DISPLAY 0.489362 (810 1305);
PAINT MONO (810 1305);
FORCEPROP 1 LASTPIN (800 1125) $PN 2
J 0
(810 1105);
DISPLAY 0.489362 (810 1105);
PAINT MONO (810 1105);
FORCEPROP 1 LAST PACK_TYPE 0402
J 0
(850 1025);
DISPLAY 0.489362 (850 1025);
PAINT SKYBLUE (850 1025);
FORCEPROP 1 LAST VOLTAGE 25V
J 0
(850 1225);
DISPLAY 0.489362 (850 1225);
PAINT SKYBLUE (850 1225);
FORCEPROP 1 LAST PART_NUMBER CH4104K1B00
J 0
(850 1075);
DISPLAY 0.489362 (850 1075);
PAINT SKYBLUE (850 1075);
FORCEPROP 1 LAST VALUE 0.1UF
J 0
(850 1275);
DISPLAY 0.489362 (850 1275);
PAINT SKYBLUE (850 1275);
FORCEPROP 1 LAST TOLERANCE 10%
J 0
(850 1175);
DISPLAY 0.489362 (850 1175);
PAINT SKYBLUE (850 1175);
FORCEPROP 1 LAST MATERIAL X7R
J 0
(850 1125);
DISPLAY 0.489362 (850 1125);
PAINT SKYBLUE (850 1125);
FORCEPROP 1 LAST PATH I100
J 0
(850 1375);
DISPLAY 0.978723 (850 1375);
PAINT WHITE (850 1375);
DISPLAY INVISIBLE (850 1375);
FORCEPROP 2 LAST CDS_LIB pure_quanta
J 0
(800 1225);
DISPLAY INVISIBLE (800 1225);
FORCEADD Q_CAP..1
(5225 4650);
FORCEPROP 1 LAST LOCATION PC122
J 0
(5275 4750);
DISPLAY 0.489362 (5275 4750);
PAINT SKYBLUE (5275 4750);
FORCEPROP 0 LAST $SEC 1
J 0
(5275 4800);
DISPLAY 0.680851 (5275 4800);
PAINT MONO (5275 4800);
DISPLAY INVISIBLE (5275 4800);
FORCEPROP 0 LAST CDS_SEC 1
J 2
(5275 4775);
DISPLAY 1.021277 (5275 4775);
DISPLAY INVISIBLE (5275 4775);
FORCEPROP 1 LASTPIN (5225 4750) $PN 1
J 0
(5235 4730);
DISPLAY 0.489362 (5235 4730);
PAINT MONO (5235 4730);
FORCEPROP 1 LASTPIN (5225 4550) $PN 2
J 0
(5235 4530);
DISPLAY 0.489362 (5235 4530);
PAINT MONO (5235 4530);
FORCEPROP 1 LAST PACK_TYPE 0402
J 0
(5275 4450);
DISPLAY 0.489362 (5275 4450);
PAINT SKYBLUE (5275 4450);
FORCEPROP 1 LAST TOLERANCE 10%
J 0
(5275 4600);
DISPLAY 0.489362 (5275 4600);
PAINT SKYBLUE (5275 4600);
FORCEPROP 1 LAST MATERIAL X7R
J 0
(5275 4550);
DISPLAY 0.489362 (5275 4550);
PAINT SKYBLUE (5275 4550);
FORCEPROP 1 LAST VOLTAGE 16V
J 0
(5275 4650);
DISPLAY 0.489362 (5275 4650);
PAINT SKYBLUE (5275 4650);
FORCEPROP 1 LAST VALUE 0.22UF
J 0
(5275 4700);
DISPLAY 0.489362 (5275 4700);
PAINT SKYBLUE (5275 4700);
FORCEPROP 1 LAST PART_NUMBER CH4223K1B00
J 0
(5275 4500);
DISPLAY 0.489362 (5275 4500);
PAINT SKYBLUE (5275 4500);
FORCEPROP 1 LAST PATH I101
J 0
(5275 4800);
DISPLAY 0.978723 (5275 4800);
PAINT WHITE (5275 4800);
DISPLAY INVISIBLE (5275 4800);
FORCEPROP 2 LAST CDS_LIB pure_quanta
J 2
(5225 4650);
DISPLAY INVISIBLE (5225 4650);
FORCEADD Q_RES..1
(4500 4775);
FORCEPROP 1 LAST LOCATION PR90
J 0
(4275 4850);
DISPLAY 0.489362 (4275 4850);
PAINT SKYBLUE (4275 4850);
FORCEPROP 0 LAST $SEC 1
J 0
(4775 4875);
DISPLAY 0.680851 (4775 4875);
PAINT MONO (4775 4875);
DISPLAY INVISIBLE (4775 4875);
FORCEPROP 0 LAST CDS_SEC 1
J 0
(4775 4875);
DISPLAY 1.021277 (4775 4875);
DISPLAY INVISIBLE (4775 4875);
FORCEPROP 1 LASTPIN (4400 4775) $PN 1
J 0
(4412 4787);
DISPLAY 0.787234 (4412 4787);
PAINT MONO (4412 4787);
DISPLAY INVISIBLE (4412 4787);
FORCEPROP 1 LASTPIN (4600 4775) $PN 2
J 0
(4562 4787);
DISPLAY 0.787234 (4562 4787);
PAINT MONO (4562 4787);
DISPLAY INVISIBLE (4562 4787);
FORCEPROP 1 LAST PACK_TYPE 0402LF
J 0
(4900 4700);
DISPLAY 0.489362 (4900 4700);
PAINT SKYBLUE (4900 4700);
FORCEPROP 1 LAST WATTAGE 1/16W
J 2
(4775 4850);
DISPLAY 0.489362 (4775 4850);
PAINT SKYBLUE (4775 4850);
FORCEPROP 1 LAST MATERIAL CHIP
J 0
(4350 4700);
DISPLAY 0.489362 (4350 4700);
PAINT SKYBLUE (4350 4700);
FORCEPROP 1 LAST TOLERANCE 1%
J 0
(4500 4850);
DISPLAY 0.489362 (4500 4850);
PAINT SKYBLUE (4500 4850);
FORCEPROP 1 LAST VALUE 4.7
J 2
(4450 4850);
DISPLAY 0.489362 (4450 4850);
PAINT SKYBLUE (4450 4850);
FORCEPROP 1 LAST PART_NUMBER CS-4702FB19
J 0
(4525 4700);
DISPLAY 0.489362 (4525 4700);
PAINT SKYBLUE (4525 4700);
FORCEPROP 2 LAST CDS_LIB pure_quanta
J 0
(4500 4775);
DISPLAY INVISIBLE (4500 4775);
FORCEPROP 1 LAST PATH I102
J 0
(4450 4925);
DISPLAY 0.978723 (4450 4925);
PAINT WHITE (4450 4925);
DISPLAY INVISIBLE (4450 4925);
FORCEADD Q_CAP..1
(5200 1825);
FORCEPROP 1 LAST LOCATION PC121
J 0
(5250 1925);
DISPLAY 0.489362 (5250 1925);
PAINT SKYBLUE (5250 1925);
FORCEPROP 0 LAST $SEC 1
J 0
(5250 1975);
DISPLAY 0.680851 (5250 1975);
PAINT MONO (5250 1975);
DISPLAY INVISIBLE (5250 1975);
FORCEPROP 0 LAST CDS_SEC 1
J 2
(5250 1950);
DISPLAY 1.021277 (5250 1950);
DISPLAY INVISIBLE (5250 1950);
FORCEPROP 1 LASTPIN (5200 1925) $PN 1
J 0
(5210 1905);
DISPLAY 0.489362 (5210 1905);
PAINT MONO (5210 1905);
FORCEPROP 1 LASTPIN (5200 1725) $PN 2
J 0
(5210 1705);
DISPLAY 0.489362 (5210 1705);
PAINT MONO (5210 1705);
FORCEPROP 1 LAST VALUE 0.22UF
J 0
(5250 1875);
DISPLAY 0.489362 (5250 1875);
PAINT SKYBLUE (5250 1875);
FORCEPROP 1 LAST VOLTAGE 16V
J 0
(5250 1825);
DISPLAY 0.489362 (5250 1825);
PAINT SKYBLUE (5250 1825);
FORCEPROP 1 LAST TOLERANCE 10%
J 0
(5250 1775);
DISPLAY 0.489362 (5250 1775);
PAINT SKYBLUE (5250 1775);
FORCEPROP 1 LAST PACK_TYPE 0402
J 0
(5250 1625);
DISPLAY 0.489362 (5250 1625);
PAINT SKYBLUE (5250 1625);
FORCEPROP 1 LAST PART_NUMBER CH4223K1B00
J 0
(5250 1675);
DISPLAY 0.489362 (5250 1675);
PAINT SKYBLUE (5250 1675);
FORCEPROP 1 LAST MATERIAL X7R
J 0
(5250 1725);
DISPLAY 0.489362 (5250 1725);
PAINT SKYBLUE (5250 1725);
FORCEPROP 1 LAST PATH I103
J 0
(5250 1975);
DISPLAY 0.978723 (5250 1975);
PAINT WHITE (5250 1975);
DISPLAY INVISIBLE (5250 1975);
FORCEPROP 2 LAST CDS_LIB pure_quanta
J 2
(5200 1825);
DISPLAY INVISIBLE (5200 1825);
FORCEADD Q_RES..1
(4475 1950);
FORCEPROP 1 LAST LOCATION PR89
J 0
(4250 2025);
DISPLAY 0.489362 (4250 2025);
PAINT SKYBLUE (4250 2025);
FORCEPROP 0 LAST $SEC 1
J 0
(4750 2050);
DISPLAY 0.680851 (4750 2050);
PAINT MONO (4750 2050);
DISPLAY INVISIBLE (4750 2050);
FORCEPROP 0 LAST CDS_SEC 1
J 0
(4750 2050);
DISPLAY 1.021277 (4750 2050);
DISPLAY INVISIBLE (4750 2050);
FORCEPROP 1 LASTPIN (4375 1950) $PN 1
J 0
(4387 1962);
DISPLAY 0.787234 (4387 1962);
PAINT MONO (4387 1962);
DISPLAY INVISIBLE (4387 1962);
FORCEPROP 1 LASTPIN (4575 1950) $PN 2
J 0
(4537 1962);
DISPLAY 0.787234 (4537 1962);
PAINT MONO (4537 1962);
DISPLAY INVISIBLE (4537 1962);
FORCEPROP 1 LAST MATERIAL CHIP
J 0
(4325 1875);
DISPLAY 0.489362 (4325 1875);
PAINT SKYBLUE (4325 1875);
FORCEPROP 1 LAST WATTAGE 1/16W
J 2
(4750 2025);
DISPLAY 0.489362 (4750 2025);
PAINT SKYBLUE (4750 2025);
FORCEPROP 1 LAST PACK_TYPE 0402LF
J 0
(4875 1875);
DISPLAY 0.489362 (4875 1875);
PAINT SKYBLUE (4875 1875);
FORCEPROP 1 LAST TOLERANCE 1%
J 0
(4475 2025);
DISPLAY 0.489362 (4475 2025);
PAINT SKYBLUE (4475 2025);
FORCEPROP 1 LAST VALUE 4.7
J 2
(4425 2025);
DISPLAY 0.489362 (4425 2025);
PAINT SKYBLUE (4425 2025);
FORCEPROP 1 LAST PART_NUMBER CS-4702FB19
J 0
(4500 1875);
DISPLAY 0.489362 (4500 1875);
PAINT SKYBLUE (4500 1875);
FORCEPROP 2 LAST CDS_LIB pure_quanta
J 0
(4475 1950);
DISPLAY INVISIBLE (4475 1950);
FORCEPROP 1 LAST PATH I104
J 0
(4425 2100);
DISPLAY 0.978723 (4425 2100);
PAINT WHITE (4425 2100);
DISPLAY INVISIBLE (4425 2100);
FORCEADD Q_CAP..1
(4075 5375);
FORCEPROP 1 LAST LOCATION PC116_3
J 0
(4125 5475);
DISPLAY 0.489362 (4125 5475);
PAINT SKYBLUE (4125 5475);
FORCEPROP 0 LAST $SEC 1
J 0
(4125 5525);
DISPLAY 0.680851 (4125 5525);
PAINT MONO (4125 5525);
DISPLAY INVISIBLE (4125 5525);
FORCEPROP 0 LAST CDS_SEC 1
J 0
(4125 5525);
DISPLAY 1.021277 (4125 5525);
DISPLAY INVISIBLE (4125 5525);
FORCEPROP 1 LASTPIN (4075 5475) $PN 1
J 0
(4085 5455);
DISPLAY 0.489362 (4085 5455);
PAINT MONO (4085 5455);
FORCEPROP 1 LASTPIN (4075 5275) $PN 2
J 0
(4085 5255);
DISPLAY 0.489362 (4085 5255);
PAINT MONO (4085 5255);
FORCEPROP 1 LAST PACK_TYPE 0402
J 0
(4125 5175);
DISPLAY 0.489362 (4125 5175);
PAINT SKYBLUE (4125 5175);
FORCEPROP 1 LAST VOLTAGE 25V
J 0
(4125 5375);
DISPLAY 0.489362 (4125 5375);
PAINT SKYBLUE (4125 5375);
FORCEPROP 1 LAST PART_NUMBER CH4104K1B00
J 0
(4125 5225);
DISPLAY 0.489362 (4125 5225);
PAINT SKYBLUE (4125 5225);
FORCEPROP 1 LAST VALUE 0.1UF
J 0
(4125 5425);
DISPLAY 0.489362 (4125 5425);
PAINT SKYBLUE (4125 5425);
FORCEPROP 1 LAST TOLERANCE 10%
J 0
(4125 5325);
DISPLAY 0.489362 (4125 5325);
PAINT SKYBLUE (4125 5325);
FORCEPROP 1 LAST MATERIAL X7R
J 0
(4125 5275);
DISPLAY 0.489362 (4125 5275);
PAINT SKYBLUE (4125 5275);
FORCEPROP 1 LAST PATH I105
J 0
(4125 5525);
DISPLAY 0.978723 (4125 5525);
PAINT WHITE (4125 5525);
DISPLAY INVISIBLE (4125 5525);
FORCEPROP 2 LAST CDS_LIB pure_quanta
J 0
(4075 5375);
DISPLAY INVISIBLE (4075 5375);
FORCEADD Q_CAP..1
(4025 2525);
FORCEPROP 1 LAST LOCATION PC115_4
J 0
(4100 2650);
DISPLAY 0.489362 (4100 2650);
PAINT SKYBLUE (4100 2650);
FORCEPROP 0 LAST $SEC 1
J 0
(4075 2675);
DISPLAY 0.680851 (4075 2675);
PAINT MONO (4075 2675);
DISPLAY INVISIBLE (4075 2675);
FORCEPROP 0 LAST CDS_SEC 1
J 0
(4075 2675);
DISPLAY 1.021277 (4075 2675);
DISPLAY INVISIBLE (4075 2675);
FORCEPROP 1 LASTPIN (4025 2625) $PN 1
J 0
(4035 2605);
DISPLAY 0.489362 (4035 2605);
PAINT MONO (4035 2605);
FORCEPROP 1 LASTPIN (4025 2425) $PN 2
J 0
(4035 2405);
DISPLAY 0.489362 (4035 2405);
PAINT MONO (4035 2405);
FORCEPROP 1 LAST PACK_TYPE 0402
J 0
(4100 2350);
DISPLAY 0.489362 (4100 2350);
PAINT SKYBLUE (4100 2350);
FORCEPROP 1 LAST VOLTAGE 25V
J 0
(4100 2550);
DISPLAY 0.489362 (4100 2550);
PAINT SKYBLUE (4100 2550);
FORCEPROP 1 LAST PART_NUMBER CH4104K1B00
J 0
(4100 2400);
DISPLAY 0.489362 (4100 2400);
PAINT SKYBLUE (4100 2400);
FORCEPROP 1 LAST VALUE 0.1UF
J 0
(4100 2600);
DISPLAY 0.489362 (4100 2600);
PAINT SKYBLUE (4100 2600);
FORCEPROP 1 LAST TOLERANCE 10%
J 0
(4100 2500);
DISPLAY 0.489362 (4100 2500);
PAINT SKYBLUE (4100 2500);
FORCEPROP 1 LAST MATERIAL X7R
J 0
(4100 2450);
DISPLAY 0.489362 (4100 2450);
PAINT SKYBLUE (4100 2450);
FORCEPROP 1 LAST PATH I106
J 0
(4075 2675);
DISPLAY 0.978723 (4075 2675);
PAINT WHITE (4075 2675);
DISPLAY INVISIBLE (4075 2675);
FORCEPROP 2 LAST CDS_LIB pure_quanta
J 0
(4025 2525);
DISPLAY INVISIBLE (4025 2525);
FORCEADD Q_CAP..1
(1625 4875);
FORCEPROP 1 LAST LOCATION PC110
J 0
(1675 4975);
DISPLAY 0.489362 (1675 4975);
PAINT SKYBLUE (1675 4975);
FORCEPROP 0 LAST $SEC 1
J 0
(1675 5025);
DISPLAY 0.680851 (1675 5025);
PAINT MONO (1675 5025);
DISPLAY INVISIBLE (1675 5025);
FORCEPROP 0 LAST CDS_SEC 1
J 0
(1675 5025);
DISPLAY 1.021277 (1675 5025);
DISPLAY INVISIBLE (1675 5025);
FORCEPROP 1 LASTPIN (1625 4975) $PN 1
J 0
(1635 4955);
DISPLAY 0.489362 (1635 4955);
PAINT MONO (1635 4955);
FORCEPROP 1 LASTPIN (1625 4775) $PN 2
J 0
(1635 4755);
DISPLAY 0.489362 (1635 4755);
PAINT MONO (1635 4755);
FORCEPROP 1 LAST PACK_TYPE C0402
J 0
(1675 4675);
DISPLAY 0.489362 (1675 4675);
PAINT SKYBLUE (1675 4675);
FORCEPROP 1 LAST VOLTAGE 10V
J 0
(1675 4875);
DISPLAY 0.489362 (1675 4875);
PAINT SKYBLUE (1675 4875);
FORCEPROP 1 LAST PART_NUMBER CH5222KEB01
J 0
(1675 4725);
DISPLAY 0.489362 (1675 4725);
PAINT SKYBLUE (1675 4725);
FORCEPROP 1 LAST VALUE 2.2UF
J 0
(1675 4925);
DISPLAY 0.489362 (1675 4925);
PAINT SKYBLUE (1675 4925);
FORCEPROP 1 LAST TOLERANCE 10%
J 0
(1675 4825);
DISPLAY 0.489362 (1675 4825);
PAINT SKYBLUE (1675 4825);
FORCEPROP 1 LAST MATERIAL X6S
J 0
(1675 4775);
DISPLAY 0.489362 (1675 4775);
PAINT SKYBLUE (1675 4775);
FORCEPROP 1 LAST PATH I107
J 0
(1675 5025);
DISPLAY 0.978723 (1675 5025);
PAINT WHITE (1675 5025);
DISPLAY INVISIBLE (1675 5025);
FORCEPROP 2 LAST CDS_LIB pure_quanta
J 0
(1625 4875);
DISPLAY INVISIBLE (1625 4875);
FORCEADD UNIVERSAL_GND..1
(1625 4675);
FORCEPROP 3 LASTPIN (1625 4725) SIG_NAME GND\g
J 0
(1635 4735);
DISPLAY 0.659574 (1635 4735);
PAINT MONO (1635 4735);
DISPLAY INVISIBLE (1635 4735);
FORCEPROP 1 LAST HDL_POWER GND
J 1
(1650 4600);
DISPLAY 0.872340 (1650 4600);
PAINT GREEN (1650 4600);
DISPLAY INVISIBLE (1650 4600);
FORCEPROP 1 LAST PATH I108
J 0
(1700 4675);
DISPLAY 0.872340 (1700 4675);
PAINT AQUA (1700 4675);
DISPLAY INVISIBLE (1700 4675);
FORCEPROP 2 LAST CDS_LIB pure_quanta_power
J 0
(1625 4675);
DISPLAY INVISIBLE (1625 4675);
FORCEADD UNIVERSAL_GND..1
(1975 5175);
FORCEPROP 3 LASTPIN (1975 5225) SIG_NAME GND\g
J 0
(1985 5235);
DISPLAY 0.659574 (1985 5235);
PAINT MONO (1985 5235);
DISPLAY INVISIBLE (1985 5235);
FORCEPROP 1 LAST HDL_POWER GND
J 1
(2000 5100);
DISPLAY 0.872340 (2000 5100);
PAINT GREEN (2000 5100);
DISPLAY INVISIBLE (2000 5100);
FORCEPROP 1 LAST PATH I109
J 0
(2050 5175);
DISPLAY 0.872340 (2050 5175);
PAINT AQUA (2050 5175);
DISPLAY INVISIBLE (2050 5175);
FORCEPROP 2 LAST CDS_LIB pure_quanta_power
J 0
(1975 5175);
DISPLAY INVISIBLE (1975 5175);
FORCEADD UNIVERSAL_GND..1
(1325 3700);
FORCEPROP 3 LASTPIN (1325 3750) SIG_NAME GND\g
J 0
(1335 3760);
DISPLAY 0.659574 (1335 3760);
PAINT MONO (1335 3760);
DISPLAY INVISIBLE (1335 3760);
FORCEPROP 1 LAST HDL_POWER GND
J 1
(1350 3625);
DISPLAY 0.872340 (1350 3625);
PAINT GREEN (1350 3625);
DISPLAY INVISIBLE (1350 3625);
FORCEPROP 1 LAST PATH I11
J 0
(1400 3700);
DISPLAY 0.872340 (1400 3700);
PAINT AQUA (1400 3700);
DISPLAY INVISIBLE (1400 3700);
FORCEPROP 2 LAST CDS_LIB pure_quanta_power
J 0
(1325 3700);
PAINT MONO (1325 3700);
DISPLAY INVISIBLE (1325 3700);
FORCEADD Q_RES..2
(1625 5425);
FORCEPROP 1 LAST LOCATION PR88
J 0
(1670 5550);
DISPLAY 0.489362 (1670 5550);
PAINT SKYBLUE (1670 5550);
FORCEPROP 0 LAST $SEC 1
J 0
(1675 5600);
DISPLAY 0.680851 (1675 5600);
PAINT MONO (1675 5600);
DISPLAY INVISIBLE (1675 5600);
FORCEPROP 0 LAST CDS_SEC 1
J 0
(1675 5600);
DISPLAY 1.021277 (1675 5600);
DISPLAY INVISIBLE (1675 5600);
FORCEPROP 1 LASTPIN (1625 5525) $PN 1
J 0
(1630 5487);
DISPLAY 0.489362 (1630 5487);
PAINT MONO (1630 5487);
FORCEPROP 1 LASTPIN (1625 5325) $PN 2
J 0
(1630 5335);
DISPLAY 0.489362 (1630 5335);
PAINT MONO (1630 5335);
FORCEPROP 1 LAST PACK_TYPE 0402LF
J 0
(1675 5250);
DISPLAY 0.489362 (1675 5250);
PAINT SKYBLUE (1675 5250);
FORCEPROP 1 LAST PART_NUMBER CS-2202FB00
J 0
(1675 5300);
DISPLAY 0.489362 (1675 5300);
PAINT SKYBLUE (1675 5300);
FORCEPROP 1 LAST VALUE 2.2
J 0
(1675 5500);
DISPLAY 0.489362 (1675 5500);
PAINT SKYBLUE (1675 5500);
FORCEPROP 1 LAST TOLERANCE 1%
J 0
(1675 5450);
DISPLAY 0.489362 (1675 5450);
PAINT SKYBLUE (1675 5450);
FORCEPROP 1 LAST MATERIAL CHIP
J 0
(1675 5350);
DISPLAY 0.489362 (1675 5350);
PAINT SKYBLUE (1675 5350);
FORCEPROP 1 LAST WATTAGE 1/16W
J 0
(1675 5400);
DISPLAY 0.489362 (1675 5400);
PAINT SKYBLUE (1675 5400);
FORCEPROP 1 LAST PATH I110
J 0
(1675 5600);
DISPLAY 0.978723 (1675 5600);
PAINT WHITE (1675 5600);
DISPLAY INVISIBLE (1675 5600);
FORCEPROP 2 LAST CDS_LIB pure_quanta
J 0
(1625 5425);
DISPLAY INVISIBLE (1625 5425);
FORCEADD Q_CAP..1
(1975 5450);
FORCEPROP 1 LAST LOCATION PC112_C1P0_3
J 0
(2025 5550);
DISPLAY 0.489362 (2025 5550);
PAINT SKYBLUE (2025 5550);
FORCEPROP 0 LAST $SEC 1
J 0
(2025 5600);
DISPLAY 0.680851 (2025 5600);
PAINT MONO (2025 5600);
DISPLAY INVISIBLE (2025 5600);
FORCEPROP 0 LAST CDS_SEC 1
J 0
(2025 5600);
DISPLAY 1.021277 (2025 5600);
DISPLAY INVISIBLE (2025 5600);
FORCEPROP 1 LASTPIN (1975 5550) $PN 1
J 0
(1985 5530);
DISPLAY 0.489362 (1985 5530);
PAINT MONO (1985 5530);
FORCEPROP 1 LASTPIN (1975 5350) $PN 2
J 0
(1985 5330);
DISPLAY 0.489362 (1985 5330);
PAINT MONO (1985 5330);
FORCEPROP 1 LAST PACK_TYPE C0402
J 0
(2025 5250);
DISPLAY 0.489362 (2025 5250);
PAINT SKYBLUE (2025 5250);
FORCEPROP 1 LAST VOLTAGE 10V
J 0
(2025 5450);
DISPLAY 0.489362 (2025 5450);
PAINT SKYBLUE (2025 5450);
FORCEPROP 1 LAST PART_NUMBER CH5222KEB01
J 0
(2025 5300);
DISPLAY 0.489362 (2025 5300);
PAINT SKYBLUE (2025 5300);
FORCEPROP 1 LAST VALUE 2.2UF
J 0
(2025 5500);
DISPLAY 0.489362 (2025 5500);
PAINT SKYBLUE (2025 5500);
FORCEPROP 1 LAST TOLERANCE 10%
J 0
(2025 5400);
DISPLAY 0.489362 (2025 5400);
PAINT SKYBLUE (2025 5400);
FORCEPROP 1 LAST MATERIAL X6S
J 0
(2025 5350);
DISPLAY 0.489362 (2025 5350);
PAINT SKYBLUE (2025 5350);
FORCEPROP 1 LAST PATH I111
J 0
(2025 5600);
DISPLAY 0.978723 (2025 5600);
PAINT WHITE (2025 5600);
DISPLAY INVISIBLE (2025 5600);
FORCEPROP 2 LAST CDS_LIB pure_quanta
J 0
(1975 5450);
DISPLAY INVISIBLE (1975 5450);
FORCEADD Q_CAP..1
(1450 2050);
FORCEPROP 1 LAST LOCATION PC109
J 0
(1500 2150);
DISPLAY 0.489362 (1500 2150);
PAINT SKYBLUE (1500 2150);
FORCEPROP 0 LAST $SEC 1
J 0
(1500 2200);
DISPLAY 0.680851 (1500 2200);
PAINT MONO (1500 2200);
DISPLAY INVISIBLE (1500 2200);
FORCEPROP 0 LAST CDS_SEC 1
J 0
(1500 2200);
DISPLAY 1.021277 (1500 2200);
DISPLAY INVISIBLE (1500 2200);
FORCEPROP 1 LASTPIN (1450 2150) $PN 1
J 0
(1460 2130);
DISPLAY 0.489362 (1460 2130);
PAINT MONO (1460 2130);
FORCEPROP 1 LASTPIN (1450 1950) $PN 2
J 0
(1460 1930);
DISPLAY 0.489362 (1460 1930);
PAINT MONO (1460 1930);
FORCEPROP 1 LAST PACK_TYPE C0402
J 0
(1500 1850);
DISPLAY 0.489362 (1500 1850);
PAINT SKYBLUE (1500 1850);
FORCEPROP 1 LAST VOLTAGE 10V
J 0
(1500 2050);
DISPLAY 0.489362 (1500 2050);
PAINT SKYBLUE (1500 2050);
FORCEPROP 1 LAST PART_NUMBER CH5222KEB01
J 0
(1500 1900);
DISPLAY 0.489362 (1500 1900);
PAINT SKYBLUE (1500 1900);
FORCEPROP 1 LAST VALUE 2.2UF
J 0
(1500 2100);
DISPLAY 0.489362 (1500 2100);
PAINT SKYBLUE (1500 2100);
FORCEPROP 1 LAST TOLERANCE 10%
J 0
(1500 2000);
DISPLAY 0.489362 (1500 2000);
PAINT SKYBLUE (1500 2000);
FORCEPROP 1 LAST MATERIAL X6S
J 0
(1500 1950);
DISPLAY 0.489362 (1500 1950);
PAINT SKYBLUE (1500 1950);
FORCEPROP 1 LAST PATH I113
J 0
(1500 2200);
DISPLAY 0.978723 (1500 2200);
PAINT WHITE (1500 2200);
DISPLAY INVISIBLE (1500 2200);
FORCEPROP 2 LAST CDS_LIB pure_quanta
J 0
(1450 2050);
DISPLAY INVISIBLE (1450 2050);
FORCEADD UNIVERSAL_GND..1
(1450 1850);
FORCEPROP 3 LASTPIN (1450 1900) SIG_NAME GND\g
J 0
(1460 1910);
DISPLAY 0.659574 (1460 1910);
PAINT MONO (1460 1910);
DISPLAY INVISIBLE (1460 1910);
FORCEPROP 1 LAST HDL_POWER GND
J 1
(1475 1775);
DISPLAY 0.872340 (1475 1775);
PAINT GREEN (1475 1775);
DISPLAY INVISIBLE (1475 1775);
FORCEPROP 1 LAST PATH I114
J 0
(1525 1850);
DISPLAY 0.872340 (1525 1850);
PAINT AQUA (1525 1850);
DISPLAY INVISIBLE (1525 1850);
FORCEPROP 2 LAST CDS_LIB pure_quanta_power
J 0
(1450 1850);
DISPLAY INVISIBLE (1450 1850);
FORCEADD UNIVERSAL_GND..1
(1800 2350);
FORCEPROP 3 LASTPIN (1800 2400) SIG_NAME GND\g
J 0
(1810 2410);
DISPLAY 0.659574 (1810 2410);
PAINT MONO (1810 2410);
DISPLAY INVISIBLE (1810 2410);
FORCEPROP 1 LAST HDL_POWER GND
J 1
(1825 2275);
DISPLAY 0.872340 (1825 2275);
PAINT GREEN (1825 2275);
DISPLAY INVISIBLE (1825 2275);
FORCEPROP 1 LAST PATH I115
J 0
(1875 2350);
DISPLAY 0.872340 (1875 2350);
PAINT AQUA (1875 2350);
DISPLAY INVISIBLE (1875 2350);
FORCEPROP 2 LAST CDS_LIB pure_quanta_power
J 0
(1800 2350);
DISPLAY INVISIBLE (1800 2350);
FORCEADD Q_RES..2
(1450 2600);
FORCEPROP 1 LAST LOCATION PR87
J 0
(1495 2725);
DISPLAY 0.489362 (1495 2725);
PAINT SKYBLUE (1495 2725);
FORCEPROP 0 LAST $SEC 1
J 0
(1500 2775);
DISPLAY 0.680851 (1500 2775);
PAINT MONO (1500 2775);
DISPLAY INVISIBLE (1500 2775);
FORCEPROP 0 LAST CDS_SEC 1
J 0
(1500 2775);
DISPLAY 1.021277 (1500 2775);
DISPLAY INVISIBLE (1500 2775);
FORCEPROP 1 LASTPIN (1450 2700) $PN 1
J 0
(1455 2662);
DISPLAY 0.489362 (1455 2662);
PAINT MONO (1455 2662);
FORCEPROP 1 LASTPIN (1450 2500) $PN 2
J 0
(1455 2510);
DISPLAY 0.489362 (1455 2510);
PAINT MONO (1455 2510);
FORCEPROP 1 LAST PACK_TYPE 0402LF
J 0
(1500 2425);
DISPLAY 0.489362 (1500 2425);
PAINT SKYBLUE (1500 2425);
FORCEPROP 1 LAST PART_NUMBER CS-2202FB00
J 0
(1500 2475);
DISPLAY 0.489362 (1500 2475);
PAINT SKYBLUE (1500 2475);
FORCEPROP 1 LAST VALUE 2.2
J 0
(1500 2675);
DISPLAY 0.489362 (1500 2675);
PAINT SKYBLUE (1500 2675);
FORCEPROP 1 LAST TOLERANCE 1%
J 0
(1500 2625);
DISPLAY 0.489362 (1500 2625);
PAINT SKYBLUE (1500 2625);
FORCEPROP 1 LAST MATERIAL CHIP
J 0
(1500 2525);
DISPLAY 0.489362 (1500 2525);
PAINT SKYBLUE (1500 2525);
FORCEPROP 1 LAST WATTAGE 1/16W
J 0
(1500 2575);
DISPLAY 0.489362 (1500 2575);
PAINT SKYBLUE (1500 2575);
FORCEPROP 1 LAST PATH I116
J 0
(1500 2775);
DISPLAY 0.978723 (1500 2775);
PAINT WHITE (1500 2775);
DISPLAY INVISIBLE (1500 2775);
FORCEPROP 2 LAST CDS_LIB pure_quanta
J 0
(1450 2600);
DISPLAY INVISIBLE (1450 2600);
FORCEADD Q_CAP..1
(1800 2625);
FORCEPROP 1 LAST LOCATION PC111_C1P0_4
J 0
(1850 2725);
DISPLAY 0.489362 (1850 2725);
PAINT SKYBLUE (1850 2725);
FORCEPROP 0 LAST $SEC 1
J 0
(1850 2775);
DISPLAY 0.680851 (1850 2775);
PAINT MONO (1850 2775);
DISPLAY INVISIBLE (1850 2775);
FORCEPROP 0 LAST CDS_SEC 1
J 0
(1850 2775);
DISPLAY 1.021277 (1850 2775);
DISPLAY INVISIBLE (1850 2775);
FORCEPROP 1 LASTPIN (1800 2725) $PN 1
J 0
(1810 2705);
DISPLAY 0.489362 (1810 2705);
PAINT MONO (1810 2705);
FORCEPROP 1 LASTPIN (1800 2525) $PN 2
J 0
(1810 2505);
DISPLAY 0.489362 (1810 2505);
PAINT MONO (1810 2505);
FORCEPROP 1 LAST PACK_TYPE C0402
J 0
(1850 2425);
DISPLAY 0.489362 (1850 2425);
PAINT SKYBLUE (1850 2425);
FORCEPROP 1 LAST VOLTAGE 10V
J 0
(1850 2625);
DISPLAY 0.489362 (1850 2625);
PAINT SKYBLUE (1850 2625);
FORCEPROP 1 LAST PART_NUMBER CH5222KEB01
J 0
(1850 2475);
DISPLAY 0.489362 (1850 2475);
PAINT SKYBLUE (1850 2475);
FORCEPROP 1 LAST VALUE 2.2UF
J 0
(1850 2675);
DISPLAY 0.489362 (1850 2675);
PAINT SKYBLUE (1850 2675);
FORCEPROP 1 LAST TOLERANCE 10%
J 0
(1850 2575);
DISPLAY 0.489362 (1850 2575);
PAINT SKYBLUE (1850 2575);
FORCEPROP 1 LAST MATERIAL X6S
J 0
(1850 2525);
DISPLAY 0.489362 (1850 2525);
PAINT SKYBLUE (1850 2525);
FORCEPROP 1 LAST PATH I117
J 0
(1850 2775);
DISPLAY 0.978723 (1850 2775);
PAINT WHITE (1850 2775);
DISPLAY INVISIBLE (1850 2775);
FORCEPROP 2 LAST CDS_LIB pure_quanta
J 0
(1800 2625);
DISPLAY INVISIBLE (1800 2625);
FORCEADD UNIVERSAL_GND..1
(825 3850);
FORCEPROP 3 LASTPIN (825 3900) SIG_NAME GND\g
J 0
(835 3910);
DISPLAY 0.659574 (835 3910);
PAINT MONO (835 3910);
DISPLAY INVISIBLE (835 3910);
FORCEPROP 1 LAST HDL_POWER GND
J 1
(850 3775);
DISPLAY 0.872340 (850 3775);
PAINT GREEN (850 3775);
DISPLAY INVISIBLE (850 3775);
FORCEPROP 1 LAST PATH I119
J 0
(900 3850);
DISPLAY 0.872340 (900 3850);
PAINT AQUA (900 3850);
DISPLAY INVISIBLE (900 3850);
FORCEPROP 2 LAST CDS_LIB pure_quanta_power
J 0
(825 3850);
DISPLAY INVISIBLE (825 3850);
FORCEADD UNIVERSAL_GND..1
(800 1025);
FORCEPROP 3 LASTPIN (800 1075) SIG_NAME GND\g
J 0
(810 1085);
DISPLAY 0.659574 (810 1085);
PAINT MONO (810 1085);
DISPLAY INVISIBLE (810 1085);
FORCEPROP 1 LAST HDL_POWER GND
J 1
(825 950);
DISPLAY 0.872340 (825 950);
PAINT GREEN (825 950);
DISPLAY INVISIBLE (825 950);
FORCEPROP 1 LAST PATH I120
J 0
(875 1025);
DISPLAY 0.872340 (875 1025);
PAINT AQUA (875 1025);
DISPLAY INVISIBLE (875 1025);
FORCEPROP 2 LAST CDS_LIB pure_quanta_power
J 0
(800 1025);
DISPLAY INVISIBLE (800 1025);
FORCEADD Q_CAP..1
(4625 1425);
FORCEPROP 1 LAST LOCATION PC191
J 0
(4675 1525);
DISPLAY 0.489362 (4675 1525);
PAINT SKYBLUE (4675 1525);
FORCEPROP 0 LAST $SEC 1
J 0
(4675 1575);
DISPLAY 0.680851 (4675 1575);
PAINT MONO (4675 1575);
DISPLAY INVISIBLE (4675 1575);
FORCEPROP 0 LAST CDS_SEC 1
J 0
(4675 1575);
DISPLAY 1.021277 (4675 1575);
DISPLAY INVISIBLE (4675 1575);
FORCEPROP 1 LASTPIN (4625 1525) $PN 1
J 0
(4635 1505);
DISPLAY 0.489362 (4635 1505);
PAINT MONO (4635 1505);
FORCEPROP 1 LASTPIN (4625 1325) $PN 2
J 0
(4635 1305);
DISPLAY 0.489362 (4635 1305);
PAINT MONO (4635 1305);
FORCEPROP 1 LAST PACK_TYPE C0402
J 0
(4675 1225);
DISPLAY 0.489362 (4675 1225);
PAINT SKYBLUE (4675 1225);
FORCEPROP 1 LAST VOLTAGE 50V
J 0
(4675 1425);
DISPLAY 0.489362 (4675 1425);
PAINT SKYBLUE (4675 1425);
FORCEPROP 1 LAST PART_NUMBER CH1566K1B09
J 0
(4675 1275);
DISPLAY 0.489362 (4675 1275);
PAINT SKYBLUE (4675 1275);
FORCEPROP 1 LAST VALUE 560PF
J 0
(4675 1475);
DISPLAY 0.489362 (4675 1475);
PAINT SKYBLUE (4675 1475);
FORCEPROP 1 LAST TOLERANCE 10%
J 0
(4675 1375);
DISPLAY 0.489362 (4675 1375);
PAINT SKYBLUE (4675 1375);
FORCEPROP 1 LAST MATERIAL EMPTY
J 0
(4675 1325);
DISPLAY 0.489362 (4675 1325);
PAINT RED (4675 1325);
FORCEPROP 1 LAST PATH I121
J 0
(4675 1575);
DISPLAY 0.978723 (4675 1575);
PAINT WHITE (4675 1575);
DISPLAY INVISIBLE (4675 1575);
FORCEPROP 2 LAST CDS_LIB pure_quanta
J 0
(4625 1425);
DISPLAY INVISIBLE (4625 1425);
FORCEADD Q_RES..2
(4625 900);
FORCEPROP 1 LAST LOCATION PR509
J 0
(4670 1025);
DISPLAY 0.489362 (4670 1025);
PAINT SKYBLUE (4670 1025);
FORCEPROP 0 LAST $SEC 1
J 0
(4675 1075);
DISPLAY 0.680851 (4675 1075);
PAINT MONO (4675 1075);
DISPLAY INVISIBLE (4675 1075);
FORCEPROP 0 LAST CDS_SEC 1
J 0
(4675 1075);
DISPLAY 1.021277 (4675 1075);
DISPLAY INVISIBLE (4675 1075);
FORCEPROP 1 LASTPIN (4625 1000) $PN 1
J 0
(4630 962);
DISPLAY 0.489362 (4630 962);
PAINT MONO (4630 962);
FORCEPROP 1 LASTPIN (4625 800) $PN 2
J 0
(4630 810);
DISPLAY 0.489362 (4630 810);
PAINT MONO (4630 810);
FORCEPROP 1 LAST PACK_TYPE 0402LF
J 0
(4665 725);
DISPLAY 0.489362 (4665 725);
PAINT SKYBLUE (4665 725);
FORCEPROP 1 LAST PART_NUMBER CS-1504FB00
J 0
(4665 775);
DISPLAY 0.489362 (4665 775);
PAINT SKYBLUE (4665 775);
FORCEPROP 1 LAST VALUE 1.5
J 0
(4670 975);
DISPLAY 0.489362 (4670 975);
PAINT SKYBLUE (4670 975);
FORCEPROP 1 LAST TOLERANCE 1%
J 0
(4670 925);
DISPLAY 0.489362 (4670 925);
PAINT SKYBLUE (4670 925);
FORCEPROP 1 LAST MATERIAL EMPTY
J 0
(4665 825);
DISPLAY 0.489362 (4665 825);
PAINT RED (4665 825);
FORCEPROP 1 LAST WATTAGE 1/8W
J 0
(4665 875);
DISPLAY 0.489362 (4665 875);
PAINT SKYBLUE (4665 875);
FORCEPROP 1 LAST PATH I122
J 0
(4675 1075);
DISPLAY 0.978723 (4675 1075);
PAINT WHITE (4675 1075);
DISPLAY INVISIBLE (4675 1075);
FORCEPROP 2 LAST CDS_LIB pure_quanta
J 0
(4625 900);
DISPLAY INVISIBLE (4625 900);
FORCEADD UNIVERSAL_GND..1
(4625 675);
FORCEPROP 3 LASTPIN (4625 725) SIG_NAME GND\g
J 0
(4635 735);
DISPLAY 0.659574 (4635 735);
PAINT MONO (4635 735);
DISPLAY INVISIBLE (4635 735);
FORCEPROP 1 LAST HDL_POWER GND
J 1
(4650 600);
DISPLAY 0.872340 (4650 600);
PAINT GREEN (4650 600);
DISPLAY INVISIBLE (4650 600);
FORCEPROP 1 LAST PATH I123
J 0
(4700 675);
DISPLAY 0.872340 (4700 675);
PAINT AQUA (4700 675);
DISPLAY INVISIBLE (4700 675);
FORCEPROP 2 LAST CDS_LIB pure_quanta_power
J 0
(4625 675);
DISPLAY INVISIBLE (4625 675);
FORCEADD Q_CAP..1
(4675 4225);
FORCEPROP 1 LAST LOCATION PC192
J 0
(4725 4325);
DISPLAY 0.489362 (4725 4325);
PAINT SKYBLUE (4725 4325);
FORCEPROP 0 LAST $SEC 1
J 0
(4725 4375);
DISPLAY 0.680851 (4725 4375);
PAINT MONO (4725 4375);
DISPLAY INVISIBLE (4725 4375);
FORCEPROP 0 LAST CDS_SEC 1
J 0
(4725 4375);
DISPLAY 1.021277 (4725 4375);
DISPLAY INVISIBLE (4725 4375);
FORCEPROP 1 LASTPIN (4675 4325) $PN 1
J 0
(4685 4305);
DISPLAY 0.489362 (4685 4305);
PAINT MONO (4685 4305);
FORCEPROP 1 LASTPIN (4675 4125) $PN 2
J 0
(4685 4105);
DISPLAY 0.489362 (4685 4105);
PAINT MONO (4685 4105);
FORCEPROP 1 LAST PACK_TYPE C0402
J 0
(4725 4025);
DISPLAY 0.489362 (4725 4025);
PAINT SKYBLUE (4725 4025);
FORCEPROP 1 LAST VOLTAGE 50V
J 0
(4725 4225);
DISPLAY 0.489362 (4725 4225);
PAINT SKYBLUE (4725 4225);
FORCEPROP 1 LAST PART_NUMBER CH1566K1B09
J 0
(4725 4075);
DISPLAY 0.489362 (4725 4075);
PAINT SKYBLUE (4725 4075);
FORCEPROP 1 LAST VALUE 560PF
J 0
(4725 4275);
DISPLAY 0.489362 (4725 4275);
PAINT SKYBLUE (4725 4275);
FORCEPROP 1 LAST TOLERANCE 10%
J 0
(4725 4175);
DISPLAY 0.489362 (4725 4175);
PAINT SKYBLUE (4725 4175);
FORCEPROP 1 LAST MATERIAL EMPTY
J 0
(4725 4125);
DISPLAY 0.489362 (4725 4125);
PAINT RED (4725 4125);
FORCEPROP 1 LAST PATH I124
J 0
(4725 4375);
DISPLAY 0.978723 (4725 4375);
PAINT WHITE (4725 4375);
DISPLAY INVISIBLE (4725 4375);
FORCEPROP 2 LAST CDS_LIB pure_quanta
J 0
(4675 4225);
DISPLAY INVISIBLE (4675 4225);
FORCEADD Q_RES..2
(4675 3675);
FORCEPROP 1 LAST LOCATION PR510
J 0
(4720 3800);
DISPLAY 0.489362 (4720 3800);
PAINT SKYBLUE (4720 3800);
FORCEPROP 0 LAST $SEC 1
J 0
(4725 3850);
DISPLAY 0.680851 (4725 3850);
PAINT MONO (4725 3850);
DISPLAY INVISIBLE (4725 3850);
FORCEPROP 0 LAST CDS_SEC 1
J 0
(4725 3850);
DISPLAY 1.021277 (4725 3850);
DISPLAY INVISIBLE (4725 3850);
FORCEPROP 1 LASTPIN (4675 3775) $PN 1
J 0
(4680 3737);
DISPLAY 0.489362 (4680 3737);
PAINT MONO (4680 3737);
FORCEPROP 1 LASTPIN (4675 3575) $PN 2
J 0
(4680 3585);
DISPLAY 0.489362 (4680 3585);
PAINT MONO (4680 3585);
FORCEPROP 1 LAST PACK_TYPE 0402LF
J 0
(4715 3500);
DISPLAY 0.489362 (4715 3500);
PAINT SKYBLUE (4715 3500);
FORCEPROP 1 LAST PART_NUMBER CS-1504FB00
J 0
(4715 3550);
DISPLAY 0.489362 (4715 3550);
PAINT SKYBLUE (4715 3550);
FORCEPROP 1 LAST VALUE 1.5
J 0
(4720 3750);
DISPLAY 0.489362 (4720 3750);
PAINT SKYBLUE (4720 3750);
FORCEPROP 1 LAST TOLERANCE 1%
J 0
(4720 3700);
DISPLAY 0.489362 (4720 3700);
PAINT SKYBLUE (4720 3700);
FORCEPROP 1 LAST MATERIAL EMPTY
J 0
(4715 3600);
DISPLAY 0.489362 (4715 3600);
PAINT RED (4715 3600);
FORCEPROP 1 LAST WATTAGE 1/8W
J 0
(4715 3650);
DISPLAY 0.489362 (4715 3650);
PAINT SKYBLUE (4715 3650);
FORCEPROP 1 LAST PATH I125
J 0
(4725 3850);
DISPLAY 0.978723 (4725 3850);
PAINT WHITE (4725 3850);
DISPLAY INVISIBLE (4725 3850);
FORCEPROP 2 LAST CDS_LIB pure_quanta
J 0
(4675 3675);
DISPLAY INVISIBLE (4675 3675);
FORCEADD UNIVERSAL_GND..1
(4675 3450);
FORCEPROP 3 LASTPIN (4675 3500) SIG_NAME GND\g
J 0
(4685 3510);
DISPLAY 0.659574 (4685 3510);
PAINT MONO (4685 3510);
DISPLAY INVISIBLE (4685 3510);
FORCEPROP 1 LAST HDL_POWER GND
J 1
(4700 3375);
DISPLAY 0.872340 (4700 3375);
PAINT GREEN (4700 3375);
DISPLAY INVISIBLE (4700 3375);
FORCEPROP 1 LAST PATH I126
J 0
(4750 3450);
DISPLAY 0.872340 (4750 3450);
PAINT AQUA (4750 3450);
DISPLAY INVISIBLE (4750 3450);
FORCEPROP 2 LAST CDS_LIB pure_quanta_power
J 0
(4675 3450);
DISPLAY INVISIBLE (4675 3450);
FORCEADD UNIVERSAL_GND..1
(6950 1150);
FORCEPROP 3 LASTPIN (6950 1200) SIG_NAME GND\g
J 0
(6960 1210);
DISPLAY 0.659574 (6960 1210);
PAINT MONO (6960 1210);
DISPLAY INVISIBLE (6960 1210);
FORCEPROP 1 LAST HDL_POWER GND
J 1
(6975 1075);
DISPLAY 0.872340 (6975 1075);
PAINT GREEN (6975 1075);
DISPLAY INVISIBLE (6975 1075);
FORCEPROP 1 LAST PATH I127
J 0
(7025 1150);
DISPLAY 0.872340 (7025 1150);
PAINT AQUA (7025 1150);
DISPLAY INVISIBLE (7025 1150);
FORCEPROP 2 LAST CDS_LIB pure_quanta_power
J 0
(6950 1150);
DISPLAY INVISIBLE (6950 1150);
FORCEADD VCC_CORE..1
(1625 5850);
FORCEPROP 3 LASTPIN (1625 5800) SIG_NAME PVDDCR_CPU1_P0_PVCC\g
J 0
(1635 5810);
DISPLAY 0.659574 (1635 5810);
PAINT MONO (1635 5810);
DISPLAY INVISIBLE (1635 5810);
FORCEPROP 1 LAST HDL_POWER PVDDCR_CPU1_P0_PVCC
J 1
(1625 5900);
DISPLAY 0.489362 (1625 5900);
PAINT GREEN (1625 5900);
FORCEPROP 1 LAST PATH I128
J 0
(1675 5875);
DISPLAY 0.872340 (1675 5875);
PAINT AQUA (1675 5875);
DISPLAY INVISIBLE (1675 5875);
FORCEPROP 2 LAST CDS_LIB pure_quanta_power
J 0
(1625 5850);
DISPLAY INVISIBLE (1625 5850);
FORCEADD VCC_CORE..1
(1450 3025);
FORCEPROP 3 LASTPIN (1450 2975) SIG_NAME PVDDCR_CPU1_P0_PVCC\g
J 0
(1460 2985);
DISPLAY 0.659574 (1460 2985);
PAINT MONO (1460 2985);
DISPLAY INVISIBLE (1460 2985);
FORCEPROP 1 LAST HDL_POWER PVDDCR_CPU1_P0_PVCC
J 1
(1450 3075);
DISPLAY 0.489362 (1450 3075);
PAINT GREEN (1450 3075);
FORCEPROP 1 LAST PATH I129
J 0
(1500 3050);
DISPLAY 0.872340 (1500 3050);
PAINT AQUA (1500 3050);
DISPLAY INVISIBLE (1500 3050);
FORCEPROP 2 LAST CDS_LIB pure_quanta_power
J 0
(1450 3025);
DISPLAY INVISIBLE (1450 3025);
FORCEADD ISL99390FRZTR5935..1
(3225 1600);
FORCEPROP 1 LAST LOCATION PU14
J 0
(2925 2475);
DISPLAY 0.489362 (2925 2475);
PAINT SKYBLUE (2925 2475);
FORCEPROP 0 LAST $SEC 1
J 0
(2925 2675);
DISPLAY 0.680851 (2925 2675);
PAINT MONO (2925 2675);
DISPLAY INVISIBLE (2925 2675);
FORCEPROP 2 LAST CDS_SEC 1
J 0
(2925 2525);
DISPLAY 1.021277 (2925 2525);
DISPLAY INVISIBLE (2925 2525);
FORCEPROP 0 LASTPIN (3625 1150) $PN 2
J 0
(3635 1160);
DISPLAY 0.489362 (3635 1160);
PAINT MONO (3635 1160);
FORCEPROP 0 LASTPIN (3625 1950) $PN 33
J 0
(3635 1960);
DISPLAY 0.489362 (3635 1960);
PAINT MONO (3635 1960);
FORCEPROP 0 LASTPIN (2775 1350) $PN 31
J 2
(2765 1360);
DISPLAY 0.489362 (2765 1360);
PAINT MONO (2765 1360);
FORCEPROP 0 LASTPIN (2775 1750) $PN 35
J 2
(2765 1760);
DISPLAY 0.489362 (2765 1760);
PAINT MONO (2765 1760);
FORCEPROP 0 LASTPIN (3625 1300) $PN 6
J 0
(3635 1310);
DISPLAY 0.489362 (3635 1310);
PAINT MONO (3635 1310);
FORCEPROP 0 LASTPIN (3625 1250) $PN 41
J 0
(3635 1260);
DISPLAY 0.489362 (3635 1260);
PAINT MONO (3635 1260);
FORCEPROP 0 LASTPIN (2775 1600) $PN 38
J 2
(2765 1610);
DISPLAY 0.489362 (2765 1610);
PAINT MONO (2765 1610);
FORCEPROP 0 LASTPIN (2775 1300) $PN 37
J 2
(2765 1310);
DISPLAY 0.489362 (2765 1310);
PAINT MONO (2765 1310);
FORCEPROP 0 LASTPIN (3625 1100) $PN 5
J 0
(3635 1110);
DISPLAY 0.489362 (3635 1110);
PAINT MONO (3635 1110);
FORCEPROP 0 LASTPIN (3625 1050) $PN 7_9-20_24
J 0
(3635 1060);
DISPLAY 0.489362 (3635 1060);
PAINT MONO (3635 1060);
FORCEPROP 0 LASTPIN (3625 1000) $PN 40
J 0
(3635 1010);
DISPLAY 0.489362 (3635 1010);
PAINT MONO (3635 1010);
FORCEPROP 0 LASTPIN (3625 1700) $PN 32
J 0
(3635 1710);
DISPLAY 0.489362 (3635 1710);
PAINT MONO (3635 1710);
FORCEPROP 0 LASTPIN (2775 2250) $PN 4
J 2
(2765 2260);
DISPLAY 0.489362 (2765 2260);
PAINT MONO (2765 2260);
FORCEPROP 0 LASTPIN (2775 1000) $PN 34
J 2
(2765 1010);
DISPLAY 0.489362 (2765 1010);
PAINT MONO (2765 1010);
FORCEPROP 0 LASTPIN (2775 1500) $PN 39
J 2
(2765 1510);
DISPLAY 0.489362 (2765 1510);
PAINT MONO (2765 1510);
FORCEPROP 0 LASTPIN (3625 1600) $PN 10_19
J 0
(3635 1610);
DISPLAY 0.489362 (3635 1610);
PAINT MONO (3635 1610);
FORCEPROP 0 LASTPIN (2775 1100) $PN 36
J 2
(2765 1110);
DISPLAY 0.489362 (2765 1110);
PAINT MONO (2765 1110);
FORCEPROP 0 LASTPIN (2775 1950) $PN 3
J 2
(2765 1960);
DISPLAY 0.489362 (2765 1960);
PAINT MONO (2765 1960);
FORCEPROP 0 LASTPIN (3625 2250) $PN 25_29
J 0
(3635 2260);
DISPLAY 0.489362 (3635 2260);
PAINT MONO (3635 2260);
FORCEPROP 0 LASTPIN (3625 2200) $PN 30
J 0
(3635 2210);
DISPLAY 0.489362 (3635 2210);
PAINT MONO (3635 2210);
FORCEPROP 0 LASTPIN (3625 1350) $PN 1
J 0
(3635 1360);
DISPLAY 0.489362 (3635 1360);
PAINT MONO (3635 1360);
FORCEPROP 1 LAST PART_NUMBER AL099390004
J 0
(2925 2400);
DISPLAY 0.489362 (2925 2400);
PAINT SKYBLUE (2925 2400);
FORCEPROP 2 LAST VALUE ISL99390FRZ-TR5935
J 0
(2925 2575);
DISPLAY 0.489362 (2925 2575);
PAINT SKYBLUE (2925 2575);
FORCEPROP 1 LAST MATERIAL IC
J 0
(2925 2325);
DISPLAY 0.489362 (2925 2325);
PAINT SKYBLUE (2925 2325);
FORCEPROP 2 LAST PART_TYPE SMLF
J 0
(2925 2625);
DISPLAY 0.638298 (2925 2625);
FORCEPROP 1 LAST PATH I14
J 0
(3225 1600);
DISPLAY 0.723404 (3225 1600);
PAINT GREEN (3225 1600);
DISPLAY INVISIBLE (3225 1600);
FORCEPROP 2 LAST CDS_LIB pure_quanta
J 0
(3225 1600);
DISPLAY INVISIBLE (3225 1600);
FORCEPROP 1 LAST NEEDS_NO_SIZE TRUE
J 0
(3225 1600);
DISPLAY 0.723404 (3225 1600);
PAINT GREEN (3225 1600);
DISPLAY INVISIBLE (3225 1600);
FORCEPROP 1 LAST CDS_LMAN_SYM_OUTLINE -300,700,250,-650
J 0
(3225 1600);
DISPLAY 0.468085 (3225 1600);
PAINT GREEN (3225 1600);
DISPLAY INVISIBLE (3225 1600);
FORCEADD UNIVERSAL_GND..1
(3875 875);
FORCEPROP 3 LASTPIN (3875 925) SIG_NAME GND\g
J 0
(3885 935);
DISPLAY 0.659574 (3885 935);
PAINT MONO (3885 935);
DISPLAY INVISIBLE (3885 935);
FORCEPROP 1 LAST HDL_POWER GND
J 1
(3900 800);
DISPLAY 0.872340 (3900 800);
PAINT GREEN (3900 800);
DISPLAY INVISIBLE (3900 800);
FORCEPROP 1 LAST PATH I15
J 0
(3950 875);
DISPLAY 0.872340 (3950 875);
PAINT AQUA (3950 875);
DISPLAY INVISIBLE (3950 875);
FORCEPROP 2 LAST CDS_LIB pure_quanta_power
J 0
(3875 875);
PAINT MONO (3875 875);
DISPLAY INVISIBLE (3875 875);
FORCEADD UNIVERSAL_GND..1
(3900 3700);
FORCEPROP 3 LASTPIN (3900 3750) SIG_NAME GND\g
J 0
(3910 3760);
DISPLAY 0.659574 (3910 3760);
PAINT MONO (3910 3760);
DISPLAY INVISIBLE (3910 3760);
FORCEPROP 1 LAST HDL_POWER GND
J 1
(3925 3625);
DISPLAY 0.872340 (3925 3625);
PAINT GREEN (3925 3625);
DISPLAY INVISIBLE (3925 3625);
FORCEPROP 1 LAST PATH I18
J 0
(3975 3700);
DISPLAY 0.872340 (3975 3700);
PAINT AQUA (3975 3700);
DISPLAY INVISIBLE (3975 3700);
FORCEPROP 2 LAST CDS_LIB pure_quanta_power
J 0
(3900 3700);
PAINT MONO (3900 3700);
DISPLAY INVISIBLE (3900 3700);
FORCEADD Q_RES..2
R 2
(1325 3925);
FORCEPROP 1 LAST LOCATION PR86
J 2
(1280 4050);
DISPLAY 0.489362 (1280 4050);
PAINT SKYBLUE (1280 4050);
FORCEPROP 0 LAST $SEC 1
J 0
(1300 4100);
DISPLAY 0.680851 (1300 4100);
PAINT MONO (1300 4100);
DISPLAY INVISIBLE (1300 4100);
FORCEPROP 0 LAST CDS_SEC 1
J 0
(1300 4100);
DISPLAY 1.021277 (1300 4100);
DISPLAY INVISIBLE (1300 4100);
FORCEPROP 1 LASTPIN (1325 4025) $PN 1
J 2
(1320 3987);
DISPLAY 0.489362 (1320 3987);
PAINT MONO (1320 3987);
FORCEPROP 1 LASTPIN (1325 3825) $PN 2
J 2
(1320 3835);
DISPLAY 0.489362 (1320 3835);
PAINT MONO (1320 3835);
FORCEPROP 1 LAST PACK_TYPE 0402LF
J 2
(1285 3750);
DISPLAY 0.489362 (1285 3750);
PAINT SKYBLUE (1285 3750);
FORCEPROP 1 LAST PART_NUMBER CS28872FB01
J 2
(1285 3800);
DISPLAY 0.489362 (1285 3800);
PAINT SKYBLUE (1285 3800);
FORCEPROP 1 LAST VALUE 8.87K
J 2
(1280 4000);
DISPLAY 0.489362 (1280 4000);
PAINT SKYBLUE (1280 4000);
FORCEPROP 1 LAST TOLERANCE 1%
J 2
(1280 3950);
DISPLAY 0.489362 (1280 3950);
PAINT SKYBLUE (1280 3950);
FORCEPROP 1 LAST MATERIAL EMPTY
J 2
(1285 3850);
DISPLAY 0.489362 (1285 3850);
PAINT RED (1285 3850);
FORCEPROP 1 LAST WATTAGE 1/16W
J 2
(1285 3900);
DISPLAY 0.489362 (1285 3900);
PAINT SKYBLUE (1285 3900);
FORCEPROP 1 LAST PATH I19
J 2
(1275 4100);
DISPLAY 0.978723 (1275 4100);
PAINT WHITE (1275 4100);
DISPLAY INVISIBLE (1275 4100);
FORCEPROP 2 LAST CDS_LIB pure_quanta
J 2
(1325 3925);
DISPLAY INVISIBLE (1325 3925);
FORCEADD Q_RES..2
R 2
(1300 1100);
FORCEPROP 1 LAST LOCATION PR85
J 2
(1255 1225);
DISPLAY 0.489362 (1255 1225);
PAINT SKYBLUE (1255 1225);
FORCEPROP 0 LAST $SEC 1
J 0
(1275 1275);
DISPLAY 0.680851 (1275 1275);
PAINT MONO (1275 1275);
DISPLAY INVISIBLE (1275 1275);
FORCEPROP 0 LAST CDS_SEC 1
J 0
(1275 1275);
DISPLAY 1.021277 (1275 1275);
DISPLAY INVISIBLE (1275 1275);
FORCEPROP 1 LASTPIN (1300 1200) $PN 1
J 2
(1295 1162);
DISPLAY 0.489362 (1295 1162);
PAINT MONO (1295 1162);
FORCEPROP 1 LASTPIN (1300 1000) $PN 2
J 2
(1295 1010);
DISPLAY 0.489362 (1295 1010);
PAINT MONO (1295 1010);
FORCEPROP 1 LAST PACK_TYPE 0402LF
J 2
(1260 925);
DISPLAY 0.489362 (1260 925);
PAINT SKYBLUE (1260 925);
FORCEPROP 1 LAST PART_NUMBER CS28872FB01
J 2
(1260 975);
DISPLAY 0.489362 (1260 975);
PAINT SKYBLUE (1260 975);
FORCEPROP 1 LAST VALUE 8.87K
J 2
(1255 1175);
DISPLAY 0.489362 (1255 1175);
PAINT SKYBLUE (1255 1175);
FORCEPROP 1 LAST TOLERANCE 1%
J 2
(1255 1125);
DISPLAY 0.489362 (1255 1125);
PAINT SKYBLUE (1255 1125);
FORCEPROP 1 LAST MATERIAL EMPTY
J 2
(1260 1025);
DISPLAY 0.489362 (1260 1025);
PAINT RED (1260 1025);
FORCEPROP 1 LAST WATTAGE 1/16W
J 2
(1260 1075);
DISPLAY 0.489362 (1260 1075);
PAINT SKYBLUE (1260 1075);
FORCEPROP 1 LAST PATH I2
J 2
(1250 1275);
DISPLAY 0.978723 (1250 1275);
PAINT WHITE (1250 1275);
DISPLAY INVISIBLE (1250 1275);
FORCEPROP 2 LAST CDS_LIB pure_quanta
J 2
(1300 1100);
DISPLAY INVISIBLE (1300 1100);
FORCEADD OFFPAGE..1
(1800 3825);
FORCEPROP 2 LAST $XR0 176 
J 0
(1374 3825);
DISPLAY 0.638298 (1374 3825);
PAINT MONO (1374 3825);
FORCEPROP 2 LAST CDS_LIB standard
J 0
(1800 3825);
DISPLAY INVISIBLE (1800 3825);
FORCEPROP 1 LAST OFFPAGE TRUE
J 0
(2125 3700);
DISPLAY 0.872340 (2125 3700);
PAINT GREEN (2125 3700);
DISPLAY INVISIBLE (2125 3700);
FORCEPROP 1 LAST COMMENT_BODY TRUE
J 0
(1925 3725);
DISPLAY 0.872340 (1925 3725);
PAINT GREEN (1925 3725);
DISPLAY INVISIBLE (1925 3725);
FORCEPROP 2 LAST PATH I21
J 0
(1375 3875);
DISPLAY 1.021277 (1375 3875);
DISPLAY INVISIBLE (1375 3875);
FORCEADD OFFPAGE..5
(1800 3925);
FORCEPROP 2 LAST $XR3 176 
J 0
(1545 3853);
DISPLAY 0.638298 (1545 3853);
PAINT MONO (1545 3853);
FORCEPROP 2 LAST $XR2 179 
J 0
(1545 3961);
DISPLAY 0.638298 (1545 3961);
PAINT MONO (1545 3961);
FORCEPROP 2 LAST $XR1 178 
J 0
(1545 3889);
DISPLAY 0.638298 (1545 3889);
PAINT MONO (1545 3889);
FORCEPROP 2 LAST $XR0 177 
J 0
(1545 3925);
DISPLAY 0.638298 (1545 3925);
PAINT MONO (1545 3925);
FORCEPROP 2 LAST CDS_LIB standard
J 0
(1800 3925);
DISPLAY INVISIBLE (1800 3925);
FORCEPROP 1 LAST OFFPAGE TRUE
J 0
(2125 3800);
DISPLAY 0.872340 (2125 3800);
PAINT GREEN (2125 3800);
DISPLAY INVISIBLE (2125 3800);
FORCEPROP 1 LAST COMMENT_BODY TRUE
J 0
(1900 3850);
DISPLAY 0.872340 (1900 3850);
PAINT GREEN (1900 3850);
DISPLAY INVISIBLE (1900 3850);
FORCEPROP 2 LAST PATH I22
J 0
(1550 4075);
DISPLAY 1.021277 (1550 4075);
DISPLAY INVISIBLE (1550 4075);
FORCEADD OFFPAGE..1
(1800 4325);
FORCEPROP 2 LAST $XR5 182 
J 0
(948 4325);
DISPLAY 0.638298 (948 4325);
PAINT MONO (948 4325);
FORCEPROP 2 LAST $XR4 181 
J 0
(1068 4325);
DISPLAY 0.638298 (1068 4325);
PAINT MONO (1068 4325);
FORCEPROP 2 LAST $XR3 179 
J 0
(1188 4325);
DISPLAY 0.638298 (1188 4325);
PAINT MONO (1188 4325);
FORCEPROP 2 LAST $XR2 178 
J 0
(1308 4325);
DISPLAY 0.638298 (1308 4325);
PAINT MONO (1308 4325);
FORCEPROP 2 LAST $XR1 177 
J 0
(1428 4325);
DISPLAY 0.638298 (1428 4325);
PAINT MONO (1428 4325);
FORCEPROP 2 LAST $XR0 176 
J 0
(1548 4325);
DISPLAY 0.638298 (1548 4325);
PAINT MONO (1548 4325);
FORCEPROP 2 LAST CDS_LIB standard
J 0
(1800 4325);
DISPLAY INVISIBLE (1800 4325);
FORCEPROP 1 LAST OFFPAGE TRUE
J 0
(2125 4200);
DISPLAY 0.872340 (2125 4200);
PAINT GREEN (2125 4200);
DISPLAY INVISIBLE (2125 4200);
FORCEPROP 1 LAST COMMENT_BODY TRUE
J 0
(1925 4225);
DISPLAY 0.872340 (1925 4225);
PAINT GREEN (1925 4225);
DISPLAY INVISIBLE (1925 4225);
FORCEPROP 2 LAST PATH I23
J 0
(1525 4375);
DISPLAY 1.021277 (1525 4375);
DISPLAY INVISIBLE (1525 4375);
FORCEADD OFFPAGE..5
(1800 4425);
FORCEPROP 2 LAST $XR0 176 
J 0
(1545 4425);
DISPLAY 0.638298 (1545 4425);
PAINT MONO (1545 4425);
FORCEPROP 2 LAST CDS_LIB standard
J 0
(1800 4425);
DISPLAY INVISIBLE (1800 4425);
FORCEPROP 1 LAST OFFPAGE TRUE
J 0
(2125 4300);
DISPLAY 0.872340 (2125 4300);
PAINT GREEN (2125 4300);
DISPLAY INVISIBLE (2125 4300);
FORCEPROP 1 LAST COMMENT_BODY TRUE
J 0
(1900 4350);
DISPLAY 0.872340 (1900 4350);
PAINT GREEN (1900 4350);
DISPLAY INVISIBLE (1900 4350);
FORCEPROP 2 LAST PATH I24
J 0
(1550 4475);
DISPLAY 1.021277 (1550 4475);
DISPLAY INVISIBLE (1550 4475);
FORCEADD ISL99390FRZTR5935..1
(3250 4425);
FORCEPROP 1 LAST LOCATION PU15
J 0
(2950 5300);
DISPLAY 0.489362 (2950 5300);
PAINT SKYBLUE (2950 5300);
FORCEPROP 0 LAST $SEC 1
J 0
(2950 5500);
DISPLAY 0.680851 (2950 5500);
PAINT MONO (2950 5500);
DISPLAY INVISIBLE (2950 5500);
FORCEPROP 2 LAST CDS_SEC 1
J 0
(2950 5350);
DISPLAY 1.021277 (2950 5350);
DISPLAY INVISIBLE (2950 5350);
FORCEPROP 0 LASTPIN (3650 3975) $PN 2
J 0
(3660 3985);
DISPLAY 0.489362 (3660 3985);
PAINT MONO (3660 3985);
FORCEPROP 0 LASTPIN (3650 4775) $PN 33
J 0
(3660 4785);
DISPLAY 0.489362 (3660 4785);
PAINT MONO (3660 4785);
FORCEPROP 0 LASTPIN (2800 4175) $PN 31
J 2
(2790 4185);
DISPLAY 0.489362 (2790 4185);
PAINT MONO (2790 4185);
FORCEPROP 0 LASTPIN (2800 4575) $PN 35
J 2
(2790 4585);
DISPLAY 0.489362 (2790 4585);
PAINT MONO (2790 4585);
FORCEPROP 0 LASTPIN (3650 4125) $PN 6
J 0
(3660 4135);
DISPLAY 0.489362 (3660 4135);
PAINT MONO (3660 4135);
FORCEPROP 0 LASTPIN (3650 4075) $PN 41
J 0
(3660 4085);
DISPLAY 0.489362 (3660 4085);
PAINT MONO (3660 4085);
FORCEPROP 0 LASTPIN (2800 4425) $PN 38
J 2
(2790 4435);
DISPLAY 0.489362 (2790 4435);
PAINT MONO (2790 4435);
FORCEPROP 0 LASTPIN (2800 4125) $PN 37
J 2
(2790 4135);
DISPLAY 0.489362 (2790 4135);
PAINT MONO (2790 4135);
FORCEPROP 0 LASTPIN (3650 3925) $PN 5
J 0
(3660 3935);
DISPLAY 0.489362 (3660 3935);
PAINT MONO (3660 3935);
FORCEPROP 0 LASTPIN (3650 3875) $PN 7_9-20_24
J 0
(3660 3885);
DISPLAY 0.489362 (3660 3885);
PAINT MONO (3660 3885);
FORCEPROP 0 LASTPIN (3650 3825) $PN 40
J 0
(3660 3835);
DISPLAY 0.489362 (3660 3835);
PAINT MONO (3660 3835);
FORCEPROP 0 LASTPIN (3650 4525) $PN 32
J 0
(3660 4535);
DISPLAY 0.489362 (3660 4535);
PAINT MONO (3660 4535);
FORCEPROP 0 LASTPIN (2800 5075) $PN 4
J 2
(2790 5085);
DISPLAY 0.489362 (2790 5085);
PAINT MONO (2790 5085);
FORCEPROP 0 LASTPIN (2800 3825) $PN 34
J 2
(2790 3835);
DISPLAY 0.489362 (2790 3835);
PAINT MONO (2790 3835);
FORCEPROP 0 LASTPIN (2800 4325) $PN 39
J 2
(2790 4335);
DISPLAY 0.489362 (2790 4335);
PAINT MONO (2790 4335);
FORCEPROP 0 LASTPIN (3650 4425) $PN 10_19
J 0
(3660 4435);
DISPLAY 0.489362 (3660 4435);
PAINT MONO (3660 4435);
FORCEPROP 0 LASTPIN (2800 3925) $PN 36
J 2
(2790 3935);
DISPLAY 0.489362 (2790 3935);
PAINT MONO (2790 3935);
FORCEPROP 0 LASTPIN (2800 4775) $PN 3
J 2
(2790 4785);
DISPLAY 0.489362 (2790 4785);
PAINT MONO (2790 4785);
FORCEPROP 0 LASTPIN (3650 5075) $PN 25_29
J 0
(3660 5085);
DISPLAY 0.489362 (3660 5085);
PAINT MONO (3660 5085);
FORCEPROP 0 LASTPIN (3650 5025) $PN 30
J 0
(3660 5035);
DISPLAY 0.489362 (3660 5035);
PAINT MONO (3660 5035);
FORCEPROP 0 LASTPIN (3650 4175) $PN 1
J 0
(3660 4185);
DISPLAY 0.489362 (3660 4185);
PAINT MONO (3660 4185);
FORCEPROP 1 LAST PART_NUMBER AL099390004
J 0
(2950 5225);
DISPLAY 0.489362 (2950 5225);
PAINT SKYBLUE (2950 5225);
FORCEPROP 2 LAST VALUE ISL99390FRZ-TR5935
J 0
(2950 5400);
DISPLAY 0.489362 (2950 5400);
PAINT SKYBLUE (2950 5400);
FORCEPROP 1 LAST MATERIAL IC
J 0
(2950 5150);
DISPLAY 0.489362 (2950 5150);
PAINT SKYBLUE (2950 5150);
FORCEPROP 2 LAST PART_TYPE SMLF
J 0
(2950 5450);
DISPLAY 0.638298 (2950 5450);
FORCEPROP 1 LAST PATH I30
J 0
(3250 4425);
DISPLAY 0.723404 (3250 4425);
PAINT GREEN (3250 4425);
DISPLAY INVISIBLE (3250 4425);
FORCEPROP 2 LAST CDS_LIB pure_quanta
J 0
(3250 4425);
DISPLAY INVISIBLE (3250 4425);
FORCEPROP 1 LAST NEEDS_NO_SIZE TRUE
J 0
(3250 4425);
DISPLAY 0.723404 (3250 4425);
PAINT GREEN (3250 4425);
DISPLAY INVISIBLE (3250 4425);
FORCEPROP 1 LAST CDS_LMAN_SYM_OUTLINE -300,700,250,-650
J 0
(3250 4425);
DISPLAY 0.468085 (3250 4425);
PAINT GREEN (3250 4425);
DISPLAY INVISIBLE (3250 4425);
FORCEADD Q_CAP..1
(4425 2500);
FORCEPROP 1 LAST LOCATION PC117_4
J 0
(4475 2650);
DISPLAY 0.489362 (4475 2650);
PAINT SKYBLUE (4475 2650);
FORCEPROP 0 LAST $SEC 1
J 0
(4475 2700);
DISPLAY 0.680851 (4475 2700);
PAINT MONO (4475 2700);
DISPLAY INVISIBLE (4475 2700);
FORCEPROP 0 LAST CDS_SEC 1
J 0
(4475 2700);
DISPLAY 1.021277 (4475 2700);
DISPLAY INVISIBLE (4475 2700);
FORCEPROP 1 LASTPIN (4425 2600) $PN 1
J 0
(4435 2580);
DISPLAY 0.489362 (4435 2580);
PAINT MONO (4435 2580);
FORCEPROP 1 LASTPIN (4425 2400) $PN 2
J 0
(4435 2380);
DISPLAY 0.489362 (4435 2380);
PAINT MONO (4435 2380);
FORCEPROP 1 LAST PACK_TYPE C0402
J 0
(4475 2400);
DISPLAY 0.489362 (4475 2400);
PAINT SKYBLUE (4475 2400);
FORCEPROP 1 LAST VOLTAGE 25V
J 0
(4475 2550);
DISPLAY 0.489362 (4475 2550);
PAINT SKYBLUE (4475 2550);
FORCEPROP 1 LAST VALUE 1UF
J 0
(4475 2600);
DISPLAY 0.489362 (4475 2600);
PAINT SKYBLUE (4475 2600);
FORCEPROP 1 LAST TOLERANCE 10%
J 0
(4475 2500);
DISPLAY 0.489362 (4475 2500);
PAINT SKYBLUE (4475 2500);
FORCEPROP 1 LAST MATERIAL X6S
J 0
(4475 2450);
DISPLAY 0.489362 (4475 2450);
PAINT SKYBLUE (4475 2450);
FORCEPROP 1 LAST PART_NUMBER CH5104KEB02
J 0
(4475 2350);
DISPLAY 0.489362 (4475 2350);
PAINT SKYBLUE (4475 2350);
FORCEPROP 1 LAST PATH I37
J 0
(4475 2650);
DISPLAY 0.978723 (4475 2650);
PAINT WHITE (4475 2650);
DISPLAY INVISIBLE (4475 2650);
FORCEPROP 2 LAST CDS_LIB pure_quanta
J 0
(4425 2500);
DISPLAY INVISIBLE (4425 2500);
FORCEADD Q_CAP..1
(4825 2500);
FORCEPROP 1 LAST LOCATION PC119_4
J 0
(4875 2650);
DISPLAY 0.489362 (4875 2650);
PAINT SKYBLUE (4875 2650);
FORCEPROP 0 LAST $SEC 1
J 0
(4875 2700);
DISPLAY 0.680851 (4875 2700);
PAINT MONO (4875 2700);
DISPLAY INVISIBLE (4875 2700);
FORCEPROP 0 LAST CDS_SEC 1
J 0
(4875 2700);
DISPLAY 1.021277 (4875 2700);
DISPLAY INVISIBLE (4875 2700);
FORCEPROP 1 LASTPIN (4825 2600) $PN 1
J 0
(4835 2580);
DISPLAY 0.489362 (4835 2580);
PAINT MONO (4835 2580);
FORCEPROP 1 LASTPIN (4825 2400) $PN 2
J 0
(4835 2380);
DISPLAY 0.489362 (4835 2380);
PAINT MONO (4835 2380);
FORCEPROP 1 LAST PACK_TYPE C0805
J 0
(4875 2400);
DISPLAY 0.489362 (4875 2400);
PAINT SKYBLUE (4875 2400);
FORCEPROP 1 LAST VOLTAGE 25V
J 0
(4875 2550);
DISPLAY 0.489362 (4875 2550);
PAINT SKYBLUE (4875 2550);
FORCEPROP 1 LAST VALUE 10UF
J 0
(4875 2600);
DISPLAY 0.489362 (4875 2600);
PAINT SKYBLUE (4875 2600);
FORCEPROP 1 LAST TOLERANCE 10%
J 0
(4875 2500);
DISPLAY 0.489362 (4875 2500);
PAINT SKYBLUE (4875 2500);
FORCEPROP 1 LAST MATERIAL X6S
J 0
(4875 2450);
DISPLAY 0.489362 (4875 2450);
PAINT SKYBLUE (4875 2450);
FORCEPROP 1 LAST PART_NUMBER CH6104KEA00
J 0
(4875 2350);
DISPLAY 0.489362 (4875 2350);
PAINT SKYBLUE (4875 2350);
FORCEPROP 1 LAST PATH I38
J 0
(4875 2650);
DISPLAY 0.978723 (4875 2650);
PAINT WHITE (4875 2650);
DISPLAY INVISIBLE (4875 2650);
FORCEPROP 2 LAST CDS_LIB pure_quanta
J 0
(4825 2500);
DISPLAY INVISIBLE (4825 2500);
FORCEADD OFFPAGE..5
(1775 1100);
FORCEPROP 2 LAST $XR3 176 
J 0
(1520 1172);
DISPLAY 0.638298 (1520 1172);
PAINT MONO (1520 1172);
FORCEPROP 2 LAST $XR2 179 
J 0
(1520 1136);
DISPLAY 0.638298 (1520 1136);
PAINT MONO (1520 1136);
FORCEPROP 2 LAST $XR1 178 
J 0
(1520 1064);
DISPLAY 0.638298 (1520 1064);
PAINT MONO (1520 1064);
FORCEPROP 2 LAST $XR0 177 
J 0
(1520 1100);
DISPLAY 0.638298 (1520 1100);
PAINT MONO (1520 1100);
FORCEPROP 2 LAST CDS_LIB standard
J 0
(1775 1100);
DISPLAY INVISIBLE (1775 1100);
FORCEPROP 1 LAST OFFPAGE TRUE
J 0
(2100 975);
DISPLAY 0.872340 (2100 975);
PAINT GREEN (2100 975);
DISPLAY INVISIBLE (2100 975);
FORCEPROP 1 LAST COMMENT_BODY TRUE
J 0
(1875 1025);
DISPLAY 0.872340 (1875 1025);
PAINT GREEN (1875 1025);
DISPLAY INVISIBLE (1875 1025);
FORCEPROP 2 LAST PATH I4
J 0
(1500 1250);
DISPLAY 1.021277 (1500 1250);
DISPLAY INVISIBLE (1500 1250);
FORCEADD Q_CAP..1
(5225 2500);
FORCEPROP 1 LAST LOCATION PC123_4
J 0
(5275 2650);
DISPLAY 0.489362 (5275 2650);
PAINT SKYBLUE (5275 2650);
FORCEPROP 0 LAST $SEC 1
J 0
(5275 2700);
DISPLAY 0.680851 (5275 2700);
PAINT MONO (5275 2700);
DISPLAY INVISIBLE (5275 2700);
FORCEPROP 0 LAST CDS_SEC 1
J 0
(5275 2700);
DISPLAY 1.021277 (5275 2700);
DISPLAY INVISIBLE (5275 2700);
FORCEPROP 1 LASTPIN (5225 2600) $PN 1
J 0
(5235 2580);
DISPLAY 0.489362 (5235 2580);
PAINT MONO (5235 2580);
FORCEPROP 1 LASTPIN (5225 2400) $PN 2
J 0
(5235 2380);
DISPLAY 0.489362 (5235 2380);
PAINT MONO (5235 2380);
FORCEPROP 1 LAST VOLTAGE 25V
J 0
(5275 2550);
DISPLAY 0.489362 (5275 2550);
PAINT SKYBLUE (5275 2550);
FORCEPROP 1 LAST VALUE 10UF
J 0
(5275 2600);
DISPLAY 0.489362 (5275 2600);
PAINT SKYBLUE (5275 2600);
FORCEPROP 1 LAST TOLERANCE 10%
J 0
(5275 2500);
DISPLAY 0.489362 (5275 2500);
PAINT SKYBLUE (5275 2500);
FORCEPROP 1 LAST MATERIAL X6S
J 0
(5275 2450);
DISPLAY 0.489362 (5275 2450);
PAINT SKYBLUE (5275 2450);
FORCEPROP 1 LAST PACK_TYPE C0805
J 0
(5275 2400);
DISPLAY 0.489362 (5275 2400);
PAINT SKYBLUE (5275 2400);
FORCEPROP 1 LAST PART_NUMBER CH6104KEA00
J 0
(5275 2350);
DISPLAY 0.489362 (5275 2350);
PAINT SKYBLUE (5275 2350);
FORCEPROP 1 LAST PATH I40
J 0
(5275 2650);
DISPLAY 0.978723 (5275 2650);
PAINT WHITE (5275 2650);
DISPLAY INVISIBLE (5275 2650);
FORCEPROP 2 LAST CDS_LIB pure_quanta
J 0
(5225 2500);
DISPLAY INVISIBLE (5225 2500);
FORCEADD UNIVERSAL_GND..1
(5600 2125);
FORCEPROP 3 LASTPIN (5600 2175) SIG_NAME GND\g
J 0
(5610 2185);
DISPLAY 0.659574 (5610 2185);
PAINT MONO (5610 2185);
DISPLAY INVISIBLE (5610 2185);
FORCEPROP 1 LAST HDL_POWER GND
J 1
(5625 2050);
DISPLAY 0.872340 (5625 2050);
PAINT GREEN (5625 2050);
DISPLAY INVISIBLE (5625 2050);
FORCEPROP 1 LAST PATH I41
J 0
(5675 2125);
DISPLAY 0.872340 (5675 2125);
PAINT AQUA (5675 2125);
DISPLAY INVISIBLE (5675 2125);
FORCEPROP 2 LAST CDS_LIB pure_quanta_power
J 0
(5600 2125);
PAINT MONO (5600 2125);
DISPLAY INVISIBLE (5600 2125);
FORCEADD Q_CAP..1
(5600 2500);
FORCEPROP 1 LAST LOCATION PC125_4
J 0
(5650 2650);
DISPLAY 0.489362 (5650 2650);
PAINT SKYBLUE (5650 2650);
FORCEPROP 0 LAST $SEC 1
J 0
(5650 2700);
DISPLAY 0.680851 (5650 2700);
PAINT MONO (5650 2700);
DISPLAY INVISIBLE (5650 2700);
FORCEPROP 0 LAST CDS_SEC 1
J 0
(5650 2700);
DISPLAY 1.021277 (5650 2700);
DISPLAY INVISIBLE (5650 2700);
FORCEPROP 1 LASTPIN (5600 2600) $PN 1
J 0
(5610 2580);
DISPLAY 0.489362 (5610 2580);
PAINT MONO (5610 2580);
FORCEPROP 1 LASTPIN (5600 2400) $PN 2
J 0
(5610 2380);
DISPLAY 0.489362 (5610 2380);
PAINT MONO (5610 2380);
FORCEPROP 1 LAST PACK_TYPE C0805
J 0
(5650 2400);
DISPLAY 0.489362 (5650 2400);
PAINT SKYBLUE (5650 2400);
FORCEPROP 1 LAST VOLTAGE 25V
J 0
(5650 2550);
DISPLAY 0.489362 (5650 2550);
PAINT SKYBLUE (5650 2550);
FORCEPROP 1 LAST PART_NUMBER CH6104KEA00
J 0
(5650 2350);
DISPLAY 0.489362 (5650 2350);
PAINT SKYBLUE (5650 2350);
FORCEPROP 1 LAST VALUE 10UF
J 0
(5650 2600);
DISPLAY 0.489362 (5650 2600);
PAINT SKYBLUE (5650 2600);
FORCEPROP 1 LAST TOLERANCE 10%
J 0
(5650 2500);
DISPLAY 0.489362 (5650 2500);
PAINT SKYBLUE (5650 2500);
FORCEPROP 1 LAST MATERIAL X6S
J 0
(5650 2450);
DISPLAY 0.489362 (5650 2450);
PAINT SKYBLUE (5650 2450);
FORCEPROP 1 LAST PATH I42
J 0
(5650 2650);
DISPLAY 0.978723 (5650 2650);
PAINT WHITE (5650 2650);
DISPLAY INVISIBLE (5650 2650);
FORCEPROP 2 LAST CDS_LIB pure_quanta
J 0
(5600 2500);
DISPLAY INVISIBLE (5600 2500);
FORCEADD VCC_CORE..1
(5600 2850);
FORCEPROP 3 LASTPIN (5600 2800) SIG_NAME SW_P12V_STBY_PVDDCR_CPU1_P0_FLT\g
J 0
(5610 2810);
DISPLAY 0.659574 (5610 2810);
PAINT MONO (5610 2810);
DISPLAY INVISIBLE (5610 2810);
FORCEPROP 1 LAST HDL_POWER SW_P12V_STBY_PVDDCR_CPU1_P0_FLT
J 1
(5600 2900);
DISPLAY 0.489362 (5600 2900);
PAINT GREEN (5600 2900);
FORCEPROP 1 LAST PATH I43
J 0
(5650 2875);
DISPLAY 0.872340 (5650 2875);
PAINT AQUA (5650 2875);
DISPLAY INVISIBLE (5650 2875);
FORCEPROP 2 LAST CDS_LIB pure_quanta_power
J 0
(5600 2850);
DISPLAY INVISIBLE (5600 2850);
FORCEADD OFFPAGE..1
(1775 1000);
FORCEPROP 2 LAST $XR0 176 
J 0
(1523 1000);
DISPLAY 0.638298 (1523 1000);
PAINT MONO (1523 1000);
FORCEPROP 2 LAST CDS_LIB standard
J 0
(1775 1000);
DISPLAY INVISIBLE (1775 1000);
FORCEPROP 1 LAST OFFPAGE TRUE
J 0
(2100 875);
DISPLAY 0.872340 (2100 875);
PAINT GREEN (2100 875);
DISPLAY INVISIBLE (2100 875);
FORCEPROP 1 LAST COMMENT_BODY TRUE
J 0
(1900 900);
DISPLAY 0.872340 (1900 900);
PAINT GREEN (1900 900);
DISPLAY INVISIBLE (1900 900);
FORCEPROP 2 LAST PATH I5
J 0
(1350 1050);
DISPLAY 1.021277 (1350 1050);
DISPLAY INVISIBLE (1350 1050);
FORCEADD Q_CAP..1
(4475 5350);
FORCEPROP 1 LAST LOCATION PC118_3
J 0
(4525 5500);
DISPLAY 0.489362 (4525 5500);
PAINT SKYBLUE (4525 5500);
FORCEPROP 0 LAST $SEC 1
J 0
(4525 5550);
DISPLAY 0.680851 (4525 5550);
PAINT MONO (4525 5550);
DISPLAY INVISIBLE (4525 5550);
FORCEPROP 0 LAST CDS_SEC 1
J 0
(4525 5550);
DISPLAY 1.021277 (4525 5550);
DISPLAY INVISIBLE (4525 5550);
FORCEPROP 1 LASTPIN (4475 5450) $PN 1
J 0
(4485 5430);
DISPLAY 0.489362 (4485 5430);
PAINT MONO (4485 5430);
FORCEPROP 1 LASTPIN (4475 5250) $PN 2
J 0
(4485 5230);
DISPLAY 0.489362 (4485 5230);
PAINT MONO (4485 5230);
FORCEPROP 1 LAST PACK_TYPE C0402
J 0
(4525 5250);
DISPLAY 0.489362 (4525 5250);
PAINT SKYBLUE (4525 5250);
FORCEPROP 1 LAST VOLTAGE 25V
J 0
(4525 5400);
DISPLAY 0.489362 (4525 5400);
PAINT SKYBLUE (4525 5400);
FORCEPROP 1 LAST VALUE 1UF
J 0
(4525 5450);
DISPLAY 0.489362 (4525 5450);
PAINT SKYBLUE (4525 5450);
FORCEPROP 1 LAST TOLERANCE 10%
J 0
(4525 5350);
DISPLAY 0.489362 (4525 5350);
PAINT SKYBLUE (4525 5350);
FORCEPROP 1 LAST MATERIAL X6S
J 0
(4525 5300);
DISPLAY 0.489362 (4525 5300);
PAINT SKYBLUE (4525 5300);
FORCEPROP 1 LAST PART_NUMBER CH5104KEB02
J 0
(4525 5200);
DISPLAY 0.489362 (4525 5200);
PAINT SKYBLUE (4525 5200);
FORCEPROP 1 LAST PATH I50
J 0
(4525 5500);
DISPLAY 0.978723 (4525 5500);
PAINT WHITE (4525 5500);
DISPLAY INVISIBLE (4525 5500);
FORCEPROP 2 LAST CDS_LIB pure_quanta
J 0
(4475 5350);
DISPLAY INVISIBLE (4475 5350);
FORCEADD Q_CAP..1
(4875 5350);
FORCEPROP 1 LAST LOCATION PC120_3
J 0
(4925 5500);
DISPLAY 0.489362 (4925 5500);
PAINT SKYBLUE (4925 5500);
FORCEPROP 0 LAST $SEC 1
J 0
(4925 5550);
DISPLAY 0.680851 (4925 5550);
PAINT MONO (4925 5550);
DISPLAY INVISIBLE (4925 5550);
FORCEPROP 0 LAST CDS_SEC 1
J 0
(4925 5550);
DISPLAY 1.021277 (4925 5550);
DISPLAY INVISIBLE (4925 5550);
FORCEPROP 1 LASTPIN (4875 5450) $PN 1
J 0
(4885 5430);
DISPLAY 0.489362 (4885 5430);
PAINT MONO (4885 5430);
FORCEPROP 1 LASTPIN (4875 5250) $PN 2
J 0
(4885 5230);
DISPLAY 0.489362 (4885 5230);
PAINT MONO (4885 5230);
FORCEPROP 1 LAST PACK_TYPE C0805
J 0
(4925 5250);
DISPLAY 0.489362 (4925 5250);
PAINT SKYBLUE (4925 5250);
FORCEPROP 1 LAST VOLTAGE 25V
J 0
(4925 5400);
DISPLAY 0.489362 (4925 5400);
PAINT SKYBLUE (4925 5400);
FORCEPROP 1 LAST VALUE 10UF
J 0
(4925 5450);
DISPLAY 0.489362 (4925 5450);
PAINT SKYBLUE (4925 5450);
FORCEPROP 1 LAST TOLERANCE 10%
J 0
(4925 5350);
DISPLAY 0.489362 (4925 5350);
PAINT SKYBLUE (4925 5350);
FORCEPROP 1 LAST MATERIAL X6S
J 0
(4925 5300);
DISPLAY 0.489362 (4925 5300);
PAINT SKYBLUE (4925 5300);
FORCEPROP 1 LAST PART_NUMBER CH6104KEA00
J 0
(4925 5200);
DISPLAY 0.489362 (4925 5200);
PAINT SKYBLUE (4925 5200);
FORCEPROP 1 LAST PATH I51
J 0
(4925 5500);
DISPLAY 0.978723 (4925 5500);
PAINT WHITE (4925 5500);
DISPLAY INVISIBLE (4925 5500);
FORCEPROP 2 LAST CDS_LIB pure_quanta
J 0
(4875 5350);
DISPLAY INVISIBLE (4875 5350);
FORCEADD Q_CAP..1
(5275 5350);
FORCEPROP 1 LAST LOCATION PC124_3
J 0
(5325 5500);
DISPLAY 0.489362 (5325 5500);
PAINT SKYBLUE (5325 5500);
FORCEPROP 0 LAST $SEC 1
J 0
(5325 5550);
DISPLAY 0.680851 (5325 5550);
PAINT MONO (5325 5550);
DISPLAY INVISIBLE (5325 5550);
FORCEPROP 0 LAST CDS_SEC 1
J 0
(5325 5550);
DISPLAY 1.021277 (5325 5550);
DISPLAY INVISIBLE (5325 5550);
FORCEPROP 1 LASTPIN (5275 5450) $PN 1
J 0
(5285 5430);
DISPLAY 0.489362 (5285 5430);
PAINT MONO (5285 5430);
FORCEPROP 1 LASTPIN (5275 5250) $PN 2
J 0
(5285 5230);
DISPLAY 0.489362 (5285 5230);
PAINT MONO (5285 5230);
FORCEPROP 1 LAST PACK_TYPE C0805
J 0
(5325 5250);
DISPLAY 0.489362 (5325 5250);
PAINT SKYBLUE (5325 5250);
FORCEPROP 1 LAST VOLTAGE 25V
J 0
(5325 5400);
DISPLAY 0.489362 (5325 5400);
PAINT SKYBLUE (5325 5400);
FORCEPROP 1 LAST PART_NUMBER CH6104KEA00
J 0
(5325 5200);
DISPLAY 0.489362 (5325 5200);
PAINT SKYBLUE (5325 5200);
FORCEPROP 1 LAST VALUE 10UF
J 0
(5325 5450);
DISPLAY 0.489362 (5325 5450);
PAINT SKYBLUE (5325 5450);
FORCEPROP 1 LAST TOLERANCE 10%
J 0
(5325 5350);
DISPLAY 0.489362 (5325 5350);
PAINT SKYBLUE (5325 5350);
FORCEPROP 1 LAST MATERIAL X6S
J 0
(5325 5300);
DISPLAY 0.489362 (5325 5300);
PAINT SKYBLUE (5325 5300);
FORCEPROP 1 LAST PATH I55
J 0
(5325 5500);
DISPLAY 0.978723 (5325 5500);
PAINT WHITE (5325 5500);
DISPLAY INVISIBLE (5325 5500);
FORCEPROP 2 LAST CDS_LIB pure_quanta
J 0
(5275 5350);
DISPLAY INVISIBLE (5275 5350);
FORCEADD Q_CAP..1
(5650 5350);
FORCEPROP 1 LAST LOCATION PC126_3
J 0
(5700 5500);
DISPLAY 0.489362 (5700 5500);
PAINT SKYBLUE (5700 5500);
FORCEPROP 0 LAST $SEC 1
J 0
(5700 5550);
DISPLAY 0.680851 (5700 5550);
PAINT MONO (5700 5550);
DISPLAY INVISIBLE (5700 5550);
FORCEPROP 0 LAST CDS_SEC 1
J 0
(5700 5550);
DISPLAY 1.021277 (5700 5550);
DISPLAY INVISIBLE (5700 5550);
FORCEPROP 1 LASTPIN (5650 5450) $PN 1
J 0
(5660 5430);
DISPLAY 0.489362 (5660 5430);
PAINT MONO (5660 5430);
FORCEPROP 1 LASTPIN (5650 5250) $PN 2
J 0
(5660 5230);
DISPLAY 0.489362 (5660 5230);
PAINT MONO (5660 5230);
FORCEPROP 1 LAST PACK_TYPE C0805
J 0
(5700 5250);
DISPLAY 0.489362 (5700 5250);
PAINT SKYBLUE (5700 5250);
FORCEPROP 1 LAST VOLTAGE 25V
J 0
(5700 5400);
DISPLAY 0.489362 (5700 5400);
PAINT SKYBLUE (5700 5400);
FORCEPROP 1 LAST PART_NUMBER CH6104KEA00
J 0
(5700 5200);
DISPLAY 0.489362 (5700 5200);
PAINT SKYBLUE (5700 5200);
FORCEPROP 1 LAST VALUE 10UF
J 0
(5700 5450);
DISPLAY 0.489362 (5700 5450);
PAINT SKYBLUE (5700 5450);
FORCEPROP 1 LAST TOLERANCE 10%
J 0
(5700 5350);
DISPLAY 0.489362 (5700 5350);
PAINT SKYBLUE (5700 5350);
FORCEPROP 1 LAST MATERIAL X6S
J 0
(5700 5300);
DISPLAY 0.489362 (5700 5300);
PAINT SKYBLUE (5700 5300);
FORCEPROP 1 LAST PATH I56
J 0
(5700 5500);
DISPLAY 0.978723 (5700 5500);
PAINT WHITE (5700 5500);
DISPLAY INVISIBLE (5700 5500);
FORCEPROP 2 LAST CDS_LIB pure_quanta
J 0
(5650 5350);
DISPLAY INVISIBLE (5650 5350);
FORCEADD UNIVERSAL_GND..1
(5650 5000);
FORCEPROP 3 LASTPIN (5650 5050) SIG_NAME GND\g
J 0
(5660 5060);
DISPLAY 0.659574 (5660 5060);
PAINT MONO (5660 5060);
DISPLAY INVISIBLE (5660 5060);
FORCEPROP 1 LAST HDL_POWER GND
J 1
(5675 4925);
DISPLAY 0.872340 (5675 4925);
PAINT GREEN (5675 4925);
DISPLAY INVISIBLE (5675 4925);
FORCEPROP 1 LAST PATH I57
J 0
(5725 5000);
DISPLAY 0.872340 (5725 5000);
PAINT AQUA (5725 5000);
DISPLAY INVISIBLE (5725 5000);
FORCEPROP 2 LAST CDS_LIB pure_quanta_power
J 0
(5650 5000);
PAINT MONO (5650 5000);
DISPLAY INVISIBLE (5650 5000);
FORCEADD VCC_CORE..1
(5650 5700);
FORCEPROP 3 LASTPIN (5650 5650) SIG_NAME SW_P12V_STBY_PVDDCR_CPU1_P0_FLT\g
J 0
(5660 5660);
DISPLAY 0.659574 (5660 5660);
PAINT MONO (5660 5660);
DISPLAY INVISIBLE (5660 5660);
FORCEPROP 1 LAST HDL_POWER SW_P12V_STBY_PVDDCR_CPU1_P0_FLT
J 1
(5650 5750);
DISPLAY 0.489362 (5650 5750);
PAINT GREEN (5650 5750);
FORCEPROP 1 LAST PATH I58
J 0
(5700 5725);
DISPLAY 0.872340 (5700 5725);
PAINT AQUA (5700 5725);
DISPLAY INVISIBLE (5700 5725);
FORCEPROP 2 LAST CDS_LIB pure_quanta_power
J 0
(5650 5700);
DISPLAY INVISIBLE (5650 5700);
FORCEADD OFFPAGE..1
(1775 1500);
FORCEPROP 2 LAST $XR5 182 
J 0
(923 1500);
DISPLAY 0.638298 (923 1500);
PAINT MONO (923 1500);
FORCEPROP 2 LAST $XR4 181 
J 0
(1043 1500);
DISPLAY 0.638298 (1043 1500);
PAINT MONO (1043 1500);
FORCEPROP 2 LAST $XR3 179 
J 0
(1163 1500);
DISPLAY 0.638298 (1163 1500);
PAINT MONO (1163 1500);
FORCEPROP 2 LAST $XR2 178 
J 0
(1283 1500);
DISPLAY 0.638298 (1283 1500);
PAINT MONO (1283 1500);
FORCEPROP 2 LAST $XR1 177 
J 0
(1403 1500);
DISPLAY 0.638298 (1403 1500);
PAINT MONO (1403 1500);
FORCEPROP 2 LAST $XR0 176 
J 0
(1523 1500);
DISPLAY 0.638298 (1523 1500);
PAINT MONO (1523 1500);
FORCEPROP 2 LAST CDS_LIB standard
J 0
(1775 1500);
DISPLAY INVISIBLE (1775 1500);
FORCEPROP 1 LAST OFFPAGE TRUE
J 0
(2100 1375);
DISPLAY 0.872340 (2100 1375);
PAINT GREEN (2100 1375);
DISPLAY INVISIBLE (2100 1375);
FORCEPROP 1 LAST COMMENT_BODY TRUE
J 0
(1900 1400);
DISPLAY 0.872340 (1900 1400);
PAINT GREEN (1900 1400);
DISPLAY INVISIBLE (1900 1400);
FORCEPROP 2 LAST PATH I6
J 0
(1525 1550);
DISPLAY 1.021277 (1525 1550);
DISPLAY INVISIBLE (1525 1550);
FORCEADD OFFPAGE..5
(1775 1600);
FORCEPROP 2 LAST $XR0 176 
J 0
(1520 1600);
DISPLAY 0.638298 (1520 1600);
PAINT MONO (1520 1600);
FORCEPROP 2 LAST CDS_LIB standard
J 0
(1775 1600);
DISPLAY INVISIBLE (1775 1600);
FORCEPROP 1 LAST OFFPAGE TRUE
J 0
(2100 1475);
DISPLAY 0.872340 (2100 1475);
PAINT GREEN (2100 1475);
DISPLAY INVISIBLE (2100 1475);
FORCEPROP 1 LAST COMMENT_BODY TRUE
J 0
(1875 1525);
DISPLAY 0.872340 (1875 1525);
PAINT GREEN (1875 1525);
DISPLAY INVISIBLE (1875 1525);
FORCEPROP 2 LAST PATH I7
J 0
(1500 1650);
DISPLAY 1.021277 (1500 1650);
DISPLAY INVISIBLE (1500 1650);
FORCEADD OFFPAGE..3
(7400 4175);
FORCEPROP 2 LAST $XR0 178 
J 0
(7734 4175);
DISPLAY 0.638298 (7734 4175);
PAINT MONO (7734 4175);
FORCEPROP 2 LAST CDS_LIB standard
J 0
(7400 4175);
DISPLAY INVISIBLE (7400 4175);
FORCEPROP 1 LAST OFFPAGE TRUE
J 0
(7725 4050);
DISPLAY 0.872340 (7725 4050);
PAINT GREEN (7725 4050);
DISPLAY INVISIBLE (7725 4050);
FORCEPROP 1 LAST COMMENT_BODY TRUE
J 0
(7350 4075);
DISPLAY 0.872340 (7350 4075);
PAINT GREEN (7350 4075);
DISPLAY INVISIBLE (7350 4075);
FORCEPROP 2 LAST PATH I73
J 0
(7600 4250);
DISPLAY 1.021277 (7600 4250);
DISPLAY INVISIBLE (7600 4250);
FORCEADD OFFPAGE..6
(5225 4175);
FORCEPROP 2 LAST $XR0 177 
J 0
(4915 4175);
DISPLAY 0.638298 (4915 4175);
PAINT MONO (4915 4175);
FORCEPROP 2 LAST CDS_LIB standard
J 0
(5225 4175);
DISPLAY INVISIBLE (5225 4175);
FORCEPROP 1 LAST OFFPAGE TRUE
J 0
(5550 4050);
DISPLAY 0.872340 (5550 4050);
PAINT GREEN (5550 4050);
DISPLAY INVISIBLE (5550 4050);
FORCEPROP 1 LAST COMMENT_BODY TRUE
J 0
(5325 4100);
DISPLAY 0.872340 (5325 4100);
PAINT GREEN (5325 4100);
DISPLAY INVISIBLE (5325 4100);
FORCEPROP 2 LAST PATH I75
J 0
(5275 4250);
DISPLAY 1.021277 (5275 4250);
DISPLAY INVISIBLE (5275 4250);
FORCEADD Q_RES..1
(5825 3325);
FORCEPROP 1 LAST LOCATION PR92
J 0
(5800 3375);
DISPLAY 0.489362 (5800 3375);
PAINT SKYBLUE (5800 3375);
FORCEPROP 0 LAST $SEC 1
J 0
(6075 3475);
DISPLAY 0.680851 (6075 3475);
PAINT MONO (6075 3475);
DISPLAY INVISIBLE (6075 3475);
FORCEPROP 0 LAST CDS_SEC 1
J 0
(6075 3475);
DISPLAY 1.021277 (6075 3475);
DISPLAY INVISIBLE (6075 3475);
FORCEPROP 1 LASTPIN (5725 3325) $PN 1
J 0
(5715 3335);
DISPLAY 0.489362 (5715 3335);
PAINT MONO (5715 3335);
FORCEPROP 1 LASTPIN (5925 3325) $PN 2
J 0
(5887 3337);
DISPLAY 0.489362 (5887 3337);
PAINT MONO (5887 3337);
FORCEPROP 1 LAST PACK_TYPE 0402LF
J 0
(5950 3275);
DISPLAY 0.489362 (5950 3275);
PAINT SKYBLUE (5950 3275);
FORCEPROP 1 LAST PART_NUMBER CS00002JB38
J 0
(5550 3275);
DISPLAY 0.489362 (5550 3275);
PAINT SKYBLUE (5550 3275);
FORCEPROP 1 LAST VALUE 0
J 2
(5600 3375);
DISPLAY 0.489362 (5600 3375);
PAINT SKYBLUE (5600 3375);
FORCEPROP 1 LAST TOLERANCE 5%
J 0
(5650 3375);
DISPLAY 0.489362 (5650 3375);
PAINT SKYBLUE (5650 3375);
FORCEPROP 1 LAST MATERIAL CHIP
J 0
(5975 3350);
DISPLAY 0.489362 (5975 3350);
PAINT SKYBLUE (5975 3350);
FORCEPROP 1 LAST WATTAGE 1/16W
J 2
(6075 3400);
DISPLAY 0.489362 (6075 3400);
PAINT SKYBLUE (6075 3400);
FORCEPROP 1 LAST PATH I76
J 0
(5775 3475);
DISPLAY 0.978723 (5775 3475);
PAINT WHITE (5775 3475);
DISPLAY INVISIBLE (5775 3475);
FORCEPROP 2 LAST CDS_LIB pure_quanta
J 0
(5825 3325);
DISPLAY INVISIBLE (5825 3325);
FORCEADD VCC_CORE..1
(8350 4525);
FORCEPROP 3 LASTPIN (8350 4475) SIG_NAME PVDDCR_CPU1_P0\g
J 0
(8360 4485);
DISPLAY 0.659574 (8360 4485);
PAINT MONO (8360 4485);
DISPLAY INVISIBLE (8360 4485);
FORCEPROP 1 LAST HDL_POWER PVDDCR_CPU1_P0
J 1
(8350 4575);
DISPLAY 0.489362 (8350 4575);
PAINT GREEN (8350 4575);
FORCEPROP 1 LAST PATH I77
J 0
(8400 4550);
DISPLAY 0.872340 (8400 4550);
PAINT AQUA (8400 4550);
DISPLAY INVISIBLE (8400 4550);
FORCEPROP 2 LAST CDS_LIB pure_quanta_power
J 0
(8350 4525);
DISPLAY INVISIBLE (8350 4525);
FORCEADD Q_CAP..1
(8350 4225);
FORCEPROP 1 LAST LOCATION PC130_3
J 0
(8400 4350);
DISPLAY 0.489362 (8400 4350);
PAINT SKYBLUE (8400 4350);
FORCEPROP 0 LAST $SEC 1
J 0
(8400 4400);
DISPLAY 0.680851 (8400 4400);
PAINT MONO (8400 4400);
DISPLAY INVISIBLE (8400 4400);
FORCEPROP 0 LAST CDS_SEC 1
J 0
(8400 4400);
DISPLAY 1.021277 (8400 4400);
DISPLAY INVISIBLE (8400 4400);
FORCEPROP 1 LASTPIN (8350 4325) $PN 1
J 0
(8360 4305);
DISPLAY 0.489362 (8360 4305);
PAINT MONO (8360 4305);
FORCEPROP 1 LASTPIN (8350 4125) $PN 2
J 0
(8360 4105);
DISPLAY 0.489362 (8360 4105);
PAINT MONO (8360 4105);
FORCEPROP 1 LAST PACK_TYPE 0805
J 0
(8400 4100);
DISPLAY 0.489362 (8400 4100);
PAINT SKYBLUE (8400 4100);
FORCEPROP 1 LAST VOLTAGE 4V
J 0
(8400 4250);
DISPLAY 0.489362 (8400 4250);
PAINT SKYBLUE (8400 4250);
FORCEPROP 1 LAST PART_NUMBER TMP_QCH622KMEA01
J 0
(8400 4050);
DISPLAY 0.489362 (8400 4050);
PAINT SKYBLUE (8400 4050);
FORCEPROP 1 LAST VALUE 22UF
J 0
(8400 4300);
DISPLAY 0.489362 (8400 4300);
PAINT SKYBLUE (8400 4300);
FORCEPROP 1 LAST TOLERANCE 20%
J 0
(8400 4200);
DISPLAY 0.489362 (8400 4200);
PAINT SKYBLUE (8400 4200);
FORCEPROP 1 LAST MATERIAL X6S
J 0
(8400 4150);
DISPLAY 0.489362 (8400 4150);
PAINT SKYBLUE (8400 4150);
FORCEPROP 1 LAST PATH I78
J 0
(8400 4375);
DISPLAY 0.978723 (8400 4375);
PAINT WHITE (8400 4375);
DISPLAY INVISIBLE (8400 4375);
FORCEPROP 2 LAST CDS_LIB pure_quanta
J 0
(8350 4225);
DISPLAY INVISIBLE (8350 4225);
FORCEADD Q_CAP..1
(7925 4225);
FORCEPROP 1 LAST LOCATION PC129_3
J 0
(7975 4350);
DISPLAY 0.489362 (7975 4350);
PAINT SKYBLUE (7975 4350);
FORCEPROP 0 LAST $SEC 1
J 0
(7975 4400);
DISPLAY 0.680851 (7975 4400);
PAINT MONO (7975 4400);
DISPLAY INVISIBLE (7975 4400);
FORCEPROP 0 LAST CDS_SEC 1
J 0
(7975 4400);
DISPLAY 1.021277 (7975 4400);
DISPLAY INVISIBLE (7975 4400);
FORCEPROP 1 LASTPIN (7925 4325) $PN 1
J 0
(7935 4305);
DISPLAY 0.489362 (7935 4305);
PAINT MONO (7935 4305);
FORCEPROP 1 LASTPIN (7925 4125) $PN 2
J 0
(7935 4105);
DISPLAY 0.489362 (7935 4105);
PAINT MONO (7935 4105);
FORCEPROP 1 LAST PACK_TYPE 0805
J 0
(7975 4100);
DISPLAY 0.489362 (7975 4100);
PAINT SKYBLUE (7975 4100);
FORCEPROP 1 LAST VOLTAGE 4V
J 0
(7975 4250);
DISPLAY 0.489362 (7975 4250);
PAINT SKYBLUE (7975 4250);
FORCEPROP 1 LAST PART_NUMBER TMP_QCH622KMEA01
J 0
(7975 4050);
DISPLAY 0.489362 (7975 4050);
PAINT SKYBLUE (7975 4050);
FORCEPROP 1 LAST VALUE 22UF
J 0
(7975 4300);
DISPLAY 0.489362 (7975 4300);
PAINT SKYBLUE (7975 4300);
FORCEPROP 1 LAST TOLERANCE 20%
J 0
(7975 4200);
DISPLAY 0.489362 (7975 4200);
PAINT SKYBLUE (7975 4200);
FORCEPROP 1 LAST MATERIAL X6S
J 0
(7975 4150);
DISPLAY 0.489362 (7975 4150);
PAINT SKYBLUE (7975 4150);
FORCEPROP 1 LAST PATH I79
J 0
(7975 4375);
DISPLAY 0.978723 (7975 4375);
PAINT WHITE (7975 4375);
DISPLAY INVISIBLE (7975 4375);
FORCEPROP 2 LAST CDS_LIB pure_quanta
J 0
(7925 4225);
DISPLAY INVISIBLE (7925 4225);
FORCEADD UNIVERSAL_GND..1
(8350 3900);
FORCEPROP 3 LASTPIN (8350 3950) SIG_NAME GND\g
J 0
(8360 3960);
DISPLAY 0.659574 (8360 3960);
PAINT MONO (8360 3960);
DISPLAY INVISIBLE (8360 3960);
FORCEPROP 1 LAST HDL_POWER GND
J 1
(8375 3825);
DISPLAY 0.872340 (8375 3825);
PAINT GREEN (8375 3825);
DISPLAY INVISIBLE (8375 3825);
FORCEPROP 1 LAST PATH I80
J 0
(8425 3900);
DISPLAY 0.872340 (8425 3900);
PAINT AQUA (8425 3900);
DISPLAY INVISIBLE (8425 3900);
FORCEPROP 2 LAST CDS_LIB pure_quanta_power
J 0
(8350 3900);
PAINT MONO (8350 3900);
DISPLAY INVISIBLE (8350 3900);
FORCEADD OFFPAGE..6
(5200 1350);
FORCEPROP 2 LAST $XR0 178 
J 0
(4920 1350);
DISPLAY 0.638298 (4920 1350);
PAINT MONO (4920 1350);
FORCEPROP 2 LAST CDS_LIB standard
J 0
(5200 1350);
DISPLAY INVISIBLE (5200 1350);
FORCEPROP 1 LAST OFFPAGE TRUE
J 0
(5525 1225);
DISPLAY 0.872340 (5525 1225);
PAINT GREEN (5525 1225);
DISPLAY INVISIBLE (5525 1225);
FORCEPROP 1 LAST COMMENT_BODY TRUE
J 0
(5300 1275);
DISPLAY 0.872340 (5300 1275);
PAINT GREEN (5300 1275);
DISPLAY INVISIBLE (5300 1275);
FORCEPROP 2 LAST PATH I91
J 0
(5250 1425);
DISPLAY 1.021277 (5250 1425);
DISPLAY INVISIBLE (5250 1425);
FORCEADD Q_RES..1
(5825 600);
FORCEPROP 1 LAST LOCATION PR91
J 0
(5800 625);
DISPLAY 0.489362 (5800 625);
PAINT SKYBLUE (5800 625);
FORCEPROP 0 LAST $SEC 1
J 0
(6075 750);
DISPLAY 0.680851 (6075 750);
PAINT MONO (6075 750);
DISPLAY INVISIBLE (6075 750);
FORCEPROP 0 LAST CDS_SEC 1
J 0
(6075 750);
DISPLAY 1.021277 (6075 750);
DISPLAY INVISIBLE (6075 750);
FORCEPROP 1 LASTPIN (5725 600) $PN 1
J 0
(5737 612);
DISPLAY 0.489362 (5737 612);
PAINT MONO (5737 612);
FORCEPROP 1 LASTPIN (5925 600) $PN 2
J 0
(5887 612);
DISPLAY 0.489362 (5887 612);
PAINT MONO (5887 612);
FORCEPROP 1 LAST PACK_TYPE 0402LF
J 0
(5950 550);
DISPLAY 0.489362 (5950 550);
PAINT SKYBLUE (5950 550);
FORCEPROP 1 LAST PART_NUMBER CS00002JB38
J 0
(5525 550);
DISPLAY 0.489362 (5525 550);
PAINT SKYBLUE (5525 550);
FORCEPROP 1 LAST VALUE 0
J 2
(5625 625);
DISPLAY 0.489362 (5625 625);
PAINT SKYBLUE (5625 625);
FORCEPROP 1 LAST TOLERANCE 5%
J 0
(5650 625);
DISPLAY 0.489362 (5650 625);
PAINT SKYBLUE (5650 625);
FORCEPROP 1 LAST MATERIAL CHIP
J 0
(5975 625);
DISPLAY 0.489362 (5975 625);
PAINT SKYBLUE (5975 625);
FORCEPROP 1 LAST WATTAGE 1/16W
J 2
(6075 675);
DISPLAY 0.489362 (6075 675);
PAINT SKYBLUE (6075 675);
FORCEPROP 1 LAST PATH I92
J 0
(5775 750);
DISPLAY 0.978723 (5775 750);
PAINT WHITE (5775 750);
DISPLAY INVISIBLE (5775 750);
FORCEPROP 2 LAST CDS_LIB pure_quanta
J 0
(5825 600);
DISPLAY INVISIBLE (5825 600);
FORCEADD VCC_CORE..1
(7900 1700);
FORCEPROP 3 LASTPIN (7900 1650) SIG_NAME PVDDCR_CPU1_P0\g
J 0
(7910 1660);
DISPLAY 0.659574 (7910 1660);
PAINT MONO (7910 1660);
DISPLAY INVISIBLE (7910 1660);
FORCEPROP 1 LAST HDL_POWER PVDDCR_CPU1_P0
J 1
(7900 1750);
DISPLAY 0.489362 (7900 1750);
PAINT GREEN (7900 1750);
FORCEPROP 1 LAST PATH I93
J 0
(7950 1725);
DISPLAY 0.872340 (7950 1725);
PAINT AQUA (7950 1725);
DISPLAY INVISIBLE (7950 1725);
FORCEPROP 2 LAST CDS_LIB pure_quanta_power
J 0
(7900 1700);
DISPLAY INVISIBLE (7900 1700);
FORCEADD UNIVERSAL_GND..1
(7900 975);
FORCEPROP 3 LASTPIN (7900 1025) SIG_NAME GND\g
J 0
(7910 1035);
DISPLAY 0.659574 (7910 1035);
PAINT MONO (7910 1035);
DISPLAY INVISIBLE (7910 1035);
FORCEPROP 1 LAST HDL_POWER GND
J 1
(7925 900);
DISPLAY 0.872340 (7925 900);
PAINT GREEN (7925 900);
DISPLAY INVISIBLE (7925 900);
FORCEPROP 1 LAST PATH I94
J 0
(7975 975);
DISPLAY 0.872340 (7975 975);
PAINT AQUA (7975 975);
DISPLAY INVISIBLE (7975 975);
FORCEPROP 2 LAST CDS_LIB pure_quanta_power
J 0
(7900 975);
PAINT MONO (7900 975);
DISPLAY INVISIBLE (7900 975);
FORCEADD Q_CAP..1
(7900 1400);
FORCEPROP 1 LAST LOCATION PC128_4
J 0
(7950 1525);
DISPLAY 0.489362 (7950 1525);
PAINT SKYBLUE (7950 1525);
FORCEPROP 0 LAST $SEC 1
J 0
(7950 1575);
DISPLAY 0.680851 (7950 1575);
PAINT MONO (7950 1575);
DISPLAY INVISIBLE (7950 1575);
FORCEPROP 0 LAST CDS_SEC 1
J 0
(7950 1575);
DISPLAY 1.021277 (7950 1575);
DISPLAY INVISIBLE (7950 1575);
FORCEPROP 1 LASTPIN (7900 1500) $PN 1
J 0
(7910 1480);
DISPLAY 0.489362 (7910 1480);
PAINT MONO (7910 1480);
FORCEPROP 1 LASTPIN (7900 1300) $PN 2
J 0
(7910 1280);
DISPLAY 0.489362 (7910 1280);
PAINT MONO (7910 1280);
FORCEPROP 1 LAST PACK_TYPE 0805
J 0
(7950 1275);
DISPLAY 0.489362 (7950 1275);
PAINT SKYBLUE (7950 1275);
FORCEPROP 1 LAST VOLTAGE 4V
J 0
(7950 1425);
DISPLAY 0.489362 (7950 1425);
PAINT SKYBLUE (7950 1425);
FORCEPROP 1 LAST PART_NUMBER TMP_QCH622KMEA01
J 0
(7950 1225);
DISPLAY 0.489362 (7950 1225);
PAINT SKYBLUE (7950 1225);
FORCEPROP 1 LAST VALUE 22UF
J 0
(7950 1475);
DISPLAY 0.489362 (7950 1475);
PAINT SKYBLUE (7950 1475);
FORCEPROP 1 LAST TOLERANCE 20%
J 0
(7950 1375);
DISPLAY 0.489362 (7950 1375);
PAINT SKYBLUE (7950 1375);
FORCEPROP 1 LAST MATERIAL X6S
J 0
(7950 1325);
DISPLAY 0.489362 (7950 1325);
PAINT SKYBLUE (7950 1325);
FORCEPROP 1 LAST PATH I95
J 0
(7950 1550);
DISPLAY 0.978723 (7950 1550);
PAINT WHITE (7950 1550);
DISPLAY INVISIBLE (7950 1550);
FORCEPROP 2 LAST CDS_LIB pure_quanta
J 0
(7900 1400);
DISPLAY INVISIBLE (7900 1400);
FORCEADD Q_CAP..1
(7475 1400);
FORCEPROP 1 LAST LOCATION PC127_4
J 0
(7525 1525);
DISPLAY 0.489362 (7525 1525);
PAINT SKYBLUE (7525 1525);
FORCEPROP 0 LAST $SEC 1
J 0
(7525 1575);
DISPLAY 0.680851 (7525 1575);
PAINT MONO (7525 1575);
DISPLAY INVISIBLE (7525 1575);
FORCEPROP 0 LAST CDS_SEC 1
J 0
(7525 1575);
DISPLAY 1.021277 (7525 1575);
DISPLAY INVISIBLE (7525 1575);
FORCEPROP 1 LASTPIN (7475 1500) $PN 1
J 0
(7485 1480);
DISPLAY 0.489362 (7485 1480);
PAINT MONO (7485 1480);
FORCEPROP 1 LASTPIN (7475 1300) $PN 2
J 0
(7485 1280);
DISPLAY 0.489362 (7485 1280);
PAINT MONO (7485 1280);
FORCEPROP 1 LAST PACK_TYPE 0805
J 0
(7525 1275);
DISPLAY 0.489362 (7525 1275);
PAINT SKYBLUE (7525 1275);
FORCEPROP 1 LAST VOLTAGE 4V
J 0
(7525 1425);
DISPLAY 0.489362 (7525 1425);
PAINT SKYBLUE (7525 1425);
FORCEPROP 1 LAST PART_NUMBER TMP_QCH622KMEA01
J 0
(7525 1225);
DISPLAY 0.489362 (7525 1225);
PAINT SKYBLUE (7525 1225);
FORCEPROP 1 LAST VALUE 22UF
J 0
(7525 1475);
DISPLAY 0.489362 (7525 1475);
PAINT SKYBLUE (7525 1475);
FORCEPROP 1 LAST TOLERANCE 20%
J 0
(7525 1375);
DISPLAY 0.489362 (7525 1375);
PAINT SKYBLUE (7525 1375);
FORCEPROP 1 LAST MATERIAL X6S
J 0
(7525 1325);
DISPLAY 0.489362 (7525 1325);
PAINT SKYBLUE (7525 1325);
FORCEPROP 1 LAST PATH I96
J 0
(7525 1550);
DISPLAY 0.978723 (7525 1550);
PAINT WHITE (7525 1550);
DISPLAY INVISIBLE (7525 1550);
FORCEPROP 2 LAST CDS_LIB pure_quanta
J 0
(7475 1400);
DISPLAY INVISIBLE (7475 1400);
FORCEADD Q_INDUCTOR4P_14..1
(6125 1475);
FORCEPROP 1 LAST LOCATION PL13
J 0
(5900 1730);
DISPLAY 0.489362 (5900 1730);
PAINT SKYBLUE (5900 1730);
FORCEPROP 0 LAST $SEC 1
J 0
(5900 1775);
DISPLAY 0.680851 (5900 1775);
PAINT MONO (5900 1775);
DISPLAY INVISIBLE (5900 1775);
FORCEPROP 0 LAST CDS_SEC 1
J 0
(5900 1775);
DISPLAY 1.021277 (5900 1775);
DISPLAY INVISIBLE (5900 1775);
FORCEPROP 0 LASTPIN (5725 1600) $PN 1
J 2
(5715 1610);
DISPLAY 0.489362 (5715 1610);
PAINT MONO (5715 1610);
FORCEPROP 0 LASTPIN (5725 1350) $PN 2
J 2
(5715 1360);
DISPLAY 0.489362 (5715 1360);
PAINT MONO (5715 1360);
FORCEPROP 0 LASTPIN (6525 1350) $PN 3
J 0
(6535 1360);
DISPLAY 0.489362 (6535 1360);
PAINT MONO (6535 1360);
FORCEPROP 0 LASTPIN (6525 1600) $PN 4
J 0
(6535 1610);
DISPLAY 0.489362 (6535 1610);
PAINT MONO (6535 1610);
FORCEPROP 1 LAST PART_NUMBER CV+15^0TZ04
J 0
(6175 1650);
DISPLAY 0.489362 (6175 1650);
PAINT SKYBLUE (6175 1650);
FORCEPROP 2 LAST VALUE 150NH
J 0
(6025 1650);
DISPLAY 0.489362 (6025 1650);
PAINT SKYBLUE (6025 1650);
FORCEPROP 1 LAST MATERIAL IND
J 0
(5925 1650);
DISPLAY 0.489362 (5925 1650);
PAINT SKYBLUE (5925 1650);
FORCEPROP 2 LAST PART_TYPE SMLF
J 0
(6050 1225);
DISPLAY 1.021277 (6050 1225);
FORCEPROP 1 LAST PATH I97
J 0
(6325 1630);
DISPLAY 0.723404 (6325 1630);
PAINT GREEN (6325 1630);
DISPLAY INVISIBLE (6325 1630);
FORCEPROP 2 LAST CDS_LIB pure_quanta
J 0
(6125 1475);
DISPLAY INVISIBLE (6125 1475);
FORCEPROP 1 LAST NEEDS_NO_SIZE TRUE
J 0
(6125 1475);
DISPLAY 0.468085 (6125 1475);
PAINT GREEN (6125 1475);
DISPLAY INVISIBLE (6125 1475);
FORCEADD Q_INDUCTOR4P_14..1
(6450 4300);
FORCEPROP 1 LAST LOCATION PL14
J 0
(6225 4555);
DISPLAY 0.489362 (6225 4555);
PAINT SKYBLUE (6225 4555);
FORCEPROP 0 LAST $SEC 1
J 0
(6225 4600);
DISPLAY 0.680851 (6225 4600);
PAINT MONO (6225 4600);
DISPLAY INVISIBLE (6225 4600);
FORCEPROP 0 LAST CDS_SEC 1
J 0
(6225 4600);
DISPLAY 1.021277 (6225 4600);
DISPLAY INVISIBLE (6225 4600);
FORCEPROP 0 LASTPIN (6050 4425) $PN 1
J 2
(6040 4435);
DISPLAY 0.489362 (6040 4435);
PAINT MONO (6040 4435);
FORCEPROP 0 LASTPIN (6050 4175) $PN 2
J 2
(6040 4185);
DISPLAY 0.489362 (6040 4185);
PAINT MONO (6040 4185);
FORCEPROP 0 LASTPIN (6850 4175) $PN 3
J 0
(6860 4185);
DISPLAY 0.489362 (6860 4185);
PAINT MONO (6860 4185);
FORCEPROP 0 LASTPIN (6850 4425) $PN 4
J 0
(6860 4435);
DISPLAY 0.489362 (6860 4435);
PAINT MONO (6860 4435);
FORCEPROP 1 LAST PART_NUMBER CV+15^0TZ04
J 0
(6500 4475);
DISPLAY 0.489362 (6500 4475);
PAINT SKYBLUE (6500 4475);
FORCEPROP 2 LAST VALUE 150NH
J 0
(6350 4475);
DISPLAY 0.489362 (6350 4475);
PAINT SKYBLUE (6350 4475);
FORCEPROP 1 LAST MATERIAL IND
J 0
(6250 4475);
DISPLAY 0.489362 (6250 4475);
PAINT SKYBLUE (6250 4475);
FORCEPROP 2 LAST PART_TYPE SMLF
J 0
(6375 4050);
DISPLAY 1.021277 (6375 4050);
FORCEPROP 1 LAST PATH I98
J 0
(6650 4455);
DISPLAY 0.723404 (6650 4455);
PAINT GREEN (6650 4455);
DISPLAY INVISIBLE (6650 4455);
FORCEPROP 1 LAST NEEDS_NO_SIZE TRUE
J 0
(6450 4300);
DISPLAY 0.468085 (6450 4300);
PAINT GREEN (6450 4300);
DISPLAY INVISIBLE (6450 4300);
FORCEPROP 2 LAST CDS_LIB pure_quanta
J 0
(6450 4300);
DISPLAY INVISIBLE (6450 4300);
FORCEADD Q_CAP..1
(825 4050);
FORCEPROP 1 LAST LOCATION PC114_3
J 0
(875 4150);
DISPLAY 0.489362 (875 4150);
PAINT SKYBLUE (875 4150);
FORCEPROP 0 LAST $SEC 1
J 0
(875 4175);
DISPLAY 0.680851 (875 4175);
PAINT MONO (875 4175);
DISPLAY INVISIBLE (875 4175);
FORCEPROP 0 LAST CDS_SEC 1
J 0
(1075 4100);
DISPLAY 1.021277 (1075 4100);
DISPLAY INVISIBLE (1075 4100);
FORCEPROP 1 LASTPIN (825 4150) $PN 1
J 0
(835 4130);
DISPLAY 0.489362 (835 4130);
PAINT MONO (835 4130);
FORCEPROP 1 LASTPIN (825 3950) $PN 2
J 0
(835 3930);
DISPLAY 0.489362 (835 3930);
PAINT MONO (835 3930);
FORCEPROP 1 LAST PACK_TYPE 0402
J 0
(875 3850);
DISPLAY 0.489362 (875 3850);
PAINT SKYBLUE (875 3850);
FORCEPROP 1 LAST VOLTAGE 25V
J 0
(875 4050);
DISPLAY 0.489362 (875 4050);
PAINT SKYBLUE (875 4050);
FORCEPROP 1 LAST PART_NUMBER CH4104K1B00
J 0
(875 3900);
DISPLAY 0.489362 (875 3900);
PAINT SKYBLUE (875 3900);
FORCEPROP 1 LAST VALUE 0.1UF
J 0
(875 4100);
DISPLAY 0.489362 (875 4100);
PAINT SKYBLUE (875 4100);
FORCEPROP 1 LAST TOLERANCE 10%
J 0
(875 4000);
DISPLAY 0.489362 (875 4000);
PAINT SKYBLUE (875 4000);
FORCEPROP 1 LAST MATERIAL X7R
J 0
(875 3950);
DISPLAY 0.489362 (875 3950);
PAINT SKYBLUE (875 3950);
FORCEPROP 1 LAST PATH I99
J 0
(875 4200);
DISPLAY 0.978723 (875 4200);
PAINT WHITE (875 4200);
DISPLAY INVISIBLE (875 4200);
FORCEPROP 2 LAST CDS_LIB pure_quanta
J 0
(825 4050);
DISPLAY INVISIBLE (825 4050);
FORCEADD DNS..1
(4650 4225);
PAINT RED (4650 4225);
FORCEPROP 1 LAST COMMENT_BODY TRUE
R 1
J 0
(4725 4000);
DISPLAY 0.872340 (4725 4000);
PAINT GREEN (4725 4000);
DISPLAY INVISIBLE (4725 4000);
FORCEPROP 2 LAST CDS_LIB mstr_misc
J 0
(4650 4225);
DISPLAY INVISIBLE (4650 4225);
FORCEADD DNS..1
(4650 3675);
PAINT RED (4650 3675);
FORCEPROP 1 LAST COMMENT_BODY TRUE
R 1
J 0
(4725 3450);
DISPLAY 0.872340 (4725 3450);
PAINT GREEN (4725 3450);
DISPLAY INVISIBLE (4725 3450);
FORCEPROP 2 LAST CDS_LIB mstr_misc
J 0
(4650 3675);
DISPLAY INVISIBLE (4650 3675);
FORCEADD DNS..1
(4600 900);
PAINT RED (4600 900);
FORCEPROP 1 LAST COMMENT_BODY TRUE
R 1
J 0
(4675 675);
DISPLAY 0.872340 (4675 675);
PAINT GREEN (4675 675);
DISPLAY INVISIBLE (4675 675);
FORCEPROP 2 LAST CDS_LIB mstr_misc
J 0
(4600 900);
DISPLAY INVISIBLE (4600 900);
FORCEADD QUANTA_TITLE_BLOCK_C..1
(9450 25);
FORCEPROP 0 LAST CDS_CON_LAST_MODIFIED Fri Mar 11 14:53:28 2022
J 0
(7565 40);
DISPLAY INVISIBLE (7565 40);
FORCEPROP 1 LAST CUSTOM_TXT_CDS <CON_LAST_MODIFIED>
J 0
(7565 40);
DISPLAY 0.978723 (7565 40);
FORCEPROP 2 LAST CUSTOM_TXT_CDS <XR_PAGE_TITLE>
J 0
(1560 5275);
DISPLAY 0.638298 (1560 5275);
PAINT PINK (1560 5275);
DISPLAY INVISIBLE (1560 5275);
FORCEPROP 1 LAST CUSTOM_TXT_CDS <NAME_2>
J 0
(6275 75);
FORCEPROP 1 LAST CUSTOM_TXT_CDS <NAME_1>
J 0
(6275 200);
FORCEPROP 1 LAST CUSTOM_TXT_CDS <Q_NUMBER>
J 0
(8047 128);
DISPLAY 1.212766 (8047 128);
FORCEPROP 1 LAST CUSTOM_TXT_CDS <Q_PROJ>
J 0
(7068 127);
DISPLAY 1.212766 (7068 127);
FORCEPROP 1 LAST CUSTOM_TXT_CDS <Q_REV>
J 0
(9266 128);
DISPLAY 1.212766 (9266 128);
FORCEPROP 1 LAST CUSTOM_TXT_CDS <CON_PAGE_NUM> OF <CON_TOTAL_PAGES>
J 0
(9004 43);
DISPLAY 0.978723 (9004 43);
FORCEPROP 1 LAST Q_TITLE PVDDCR_CPU1_P0 VR PHASE 3&4
J 0
(150 75);
DISPLAY 2.446809 (150 75);
PAINT GREEN (150 75);
FORCEPROP 1 LAST Q_DEPT BU9
J 1
(5687 74);
DISPLAY 1.957447 (5687 74);
PAINT GREEN (5687 74);
FORCEPROP 1 LAST COMMENT_BODY TRUE
J 0
(9462 12);
DISPLAY 0.978723 (9462 12);
PAINT GREEN (9462 12);
DISPLAY INVISIBLE (9462 12);
FORCEPROP 1 LAST CDS_LMAN_SYM_OUTLINE -9475,6775,100,-125
J 0
(9450 25);
DISPLAY 0.468085 (9450 25);
PAINT GREEN (9450 25);
DISPLAY INVISIBLE (9450 25);
FORCEPROP 2 LAST CDS_LIB pure_quanta
J 0
(9450 25);
DISPLAY INVISIBLE (9450 25);
FORCEPROP 2 LAST PAGE_BORDER TRUE
J 0
(1560 5275);
DISPLAY 0.638298 (1560 5275);
PAINT PINK (1560 5275);
DISPLAY INVISIBLE (1560 5275);
FORCEPROP 2 LAST CDS_XR_PAGE_TITLE CR-178 : @T6G_MB_LIB.T6G(SCH_1):PAGE178
J 0
(1560 5275);
DISPLAY 0.638298 (1560 5275);
PAINT PINK (1560 5275);
DISPLAY INVISIBLE (1560 5275);
FORCEADD DNS..1
(4600 1425);
PAINT RED (4600 1425);
FORCEPROP 1 LAST COMMENT_BODY TRUE
R 1
J 0
(4675 1200);
DISPLAY 0.872340 (4675 1200);
PAINT GREEN (4675 1200);
DISPLAY INVISIBLE (4675 1200);
FORCEPROP 2 LAST CDS_LIB mstr_misc
J 0
(4600 1425);
DISPLAY INVISIBLE (4600 1425);
FORCEADD DNS..1
(1300 1075);
PAINT RED (1300 1075);
FORCEPROP 1 LAST COMMENT_BODY TRUE
R 1
J 0
(1375 850);
DISPLAY 0.872340 (1375 850);
PAINT GREEN (1375 850);
DISPLAY INVISIBLE (1375 850);
FORCEPROP 2 LAST CDS_LIB mstr_misc
J 0
(1300 1075);
PAINT MONO (1300 1075);
DISPLAY INVISIBLE (1300 1075);
FORCEADD DNS..1
(1325 3900);
PAINT RED (1325 3900);
FORCEPROP 1 LAST COMMENT_BODY TRUE
R 1
J 0
(1400 3675);
DISPLAY 0.872340 (1400 3675);
PAINT GREEN (1400 3675);
DISPLAY INVISIBLE (1400 3675);
FORCEPROP 2 LAST CDS_LIB mstr_misc
J 0
(1325 3900);
PAINT MONO (1325 3900);
DISPLAY INVISIBLE (1325 3900);
WIRE 16 -1 (1300 1000)(1300 925);
WIRE 16 -1 (1625 4775)(1625 4725);
WIRE 16 -1 (1975 5350)(1975 5225);
WIRE 16 -1 (1325 3825)(1325 3750);
WIRE 16 -1 (1450 1950)(1450 1900);
WIRE 16 -1 (1800 2525)(1800 2400);
WIRE 16 -1 (825 3900)(825 3950);
WIRE 16 -1 (800 1075)(800 1125);
WIRE 16 -1 (4625 800)(4625 725);
WIRE 16 -1 (4675 3575)(4675 3500);
WIRE 16 -1 (4575 1950)(5200 1950);
FORCEPROP 2 LAST SIG_NAME SW_PVDDCR_CPU1_P0_BOOT4_R
J 0
(4640 1960);
DISPLAY 0.489362 (4640 1960);
FORCEPROP 2 LASTPROP $XRERR UNIQUE?
J 0
(4400 1960);
DISPLAY 0.638298 (4400 1960);
PAINT MONO (4400 1960);
DISPLAY INVISIBLE (4400 1960);
WIRE 16 -1 (5200 1950)(5200 1925);
WIRE 16 -1 (5600 2175)(5600 2250);
WIRE 16 -1 (5600 2400)(5600 2250);
WIRE 16 -1 (5225 2250)(5600 2250);
WIRE 16 -1 (5225 2400)(5225 2250);
WIRE 16 -1 (4825 2250)(5225 2250);
WIRE 16 -1 (4825 2400)(4825 2250);
WIRE 16 -1 (4825 2250)(4425 2250);
WIRE 16 -1 (4425 2400)(4425 2250);
WIRE 16 -1 (4025 2250)(4425 2250);
WIRE 16 -1 (4025 2425)(4025 2250);
WIRE 16 -1 (4600 4775)(5225 4775);
FORCEPROP 2 LAST SIG_NAME SW_PVDDCR_CPU1_P0_BOOT3_R
J 0
(4715 4785);
DISPLAY 0.489362 (4715 4785);
FORCEPROP 2 LASTPROP $XRERR UNIQUE?
J 0
(4475 4785);
DISPLAY 0.638298 (4475 4785);
PAINT MONO (4475 4785);
DISPLAY INVISIBLE (4475 4785);
WIRE 16 -1 (5225 4775)(5225 4750);
WIRE 16 -1 (5650 5050)(5650 5100);
WIRE 16 -1 (5650 5250)(5650 5100);
WIRE 16 -1 (5275 5100)(5650 5100);
WIRE 16 -1 (5275 5250)(5275 5100);
WIRE 16 -1 (4875 5100)(5275 5100);
WIRE 16 -1 (4875 5250)(4875 5100);
WIRE 16 -1 (4875 5100)(4475 5100);
WIRE 16 -1 (4475 5250)(4475 5100);
WIRE 16 -1 (4075 5100)(4475 5100);
WIRE 16 -1 (4075 5275)(4075 5100);
WIRE 16 -1 (4675 4425)(6050 4425);
WIRE 16 -1 (4675 4325)(4675 4425);
WIRE 16 -1 (4675 4425)(3650 4425);
FORCEPROP 2 LAST SIG_NAME SW_PVDDCR_CPU1_P0_SW3
J 0
(3840 4435);
DISPLAY 0.489362 (3840 4435);
FORCEPROP 2 LASTPROP $XRERR UNIQUE?
J 0
(3600 4435);
DISPLAY 0.638298 (3600 4435);
PAINT MONO (3600 4435);
DISPLAY INVISIBLE (3600 4435);
WIRE 16 -1 (3650 4775)(4400 4775);
FORCEPROP 2 LAST SIG_NAME SW_PVDDCR_CPU1_P0_BOOT3
J 0
(3815 4785);
DISPLAY 0.489362 (3815 4785);
FORCEPROP 2 LASTPROP $XRERR UNIQUE?
J 0
(3575 4785);
DISPLAY 0.638298 (3575 4785);
PAINT MONO (3575 4785);
DISPLAY INVISIBLE (3575 4785);
WIRE 16 -1 (3650 4525)(5225 4525);
FORCEPROP 2 LAST SIG_NAME SW_PVDDCR_CPU1_P0_BOOTR3
J 0
(3840 4535);
DISPLAY 0.489362 (3840 4535);
FORCEPROP 2 LASTPROP $XRERR UNIQUE?
J 0
(3600 4535);
DISPLAY 0.638298 (3600 4535);
PAINT MONO (3600 4535);
DISPLAY INVISIBLE (3600 4535);
WIRE 16 -1 (5225 4525)(5225 4550);
WIRE 16 -1 (7900 1175)(7475 1175);
WIRE 16 -1 (7900 1175)(7900 1300);
WIRE 16 -1 (7900 1025)(7900 1175);
WIRE 16 -1 (7475 1175)(7475 1300);
WIRE 16 -1 (7900 1650)(7900 1600);
WIRE 16 -1 (7900 1600)(7900 1500);
WIRE 16 -1 (7475 1600)(7900 1600);
WIRE 16 -1 (7225 1600)(7475 1600);
WIRE 16 -1 (7475 1600)(7475 1500);
WIRE 16 -1 (6525 1600)(7225 1600);
WIRE 16 -1 (7225 600)(7225 1600);
WIRE 16 -1 (7225 600)(5925 600);
WIRE 16 -1 (8350 4000)(7925 4000);
WIRE 16 -1 (8350 4125)(8350 4000);
WIRE 16 -1 (8350 3950)(8350 4000);
WIRE 16 -1 (7925 4000)(7925 4125);
WIRE 16 -1 (8350 4325)(8350 4425);
WIRE 16 -1 (8350 4475)(8350 4425);
WIRE 16 -1 (7925 4425)(8350 4425);
WIRE 16 -1 (7925 4425)(7700 4425);
WIRE 16 -1 (7925 4425)(7925 4325);
WIRE 16 -1 (7700 4425)(6850 4425);
WIRE 16 -1 (7700 3325)(7700 4425);
WIRE 16 -1 (5925 3325)(7700 3325);
WIRE 16 -1 (5650 5450)(5650 5600);
WIRE 16 -1 (5650 5650)(5650 5600);
WIRE 16 -1 (5275 5600)(5650 5600);
WIRE 16 -1 (5275 5450)(5275 5600);
WIRE 16 -1 (4875 5600)(5275 5600);
WIRE 16 -1 (4875 5600)(4875 5450);
WIRE 16 -1 (4475 5600)(4875 5600);
WIRE 16 -1 (4475 5450)(4475 5600);
WIRE 16 -1 (4475 5600)(4075 5600);
WIRE 16 -1 (4075 5475)(4075 5600);
WIRE 16 -1 (4075 5600)(3825 5600);
WIRE 16 -1 (3825 5600)(3825 5075);
WIRE 16 -1 (3650 5075)(3825 5075);
WIRE 16 -1 (3825 5025)(3825 5075);
WIRE 16 -1 (3650 5025)(3825 5025);
WIRE 16 -1 (5600 2800)(5600 2750);
WIRE 16 -1 (5600 2600)(5600 2750);
WIRE 16 -1 (5225 2750)(5600 2750);
WIRE 16 -1 (5225 2600)(5225 2750);
WIRE 16 -1 (4825 2750)(5225 2750);
WIRE 16 -1 (4825 2750)(4825 2600);
WIRE 16 -1 (4425 2750)(4825 2750);
WIRE 16 -1 (4425 2600)(4425 2750);
WIRE 16 -1 (4425 2750)(4025 2750);
WIRE 16 -1 (4025 2625)(4025 2750);
WIRE 16 -1 (4025 2750)(3800 2750);
WIRE 16 -1 (3800 2750)(3800 2250);
WIRE 16 -1 (3625 2250)(3800 2250);
WIRE 16 -1 (3800 2200)(3800 2250);
WIRE 16 -1 (3625 2200)(3800 2200);
WIRE 16 -1 (3900 3875)(3900 3825);
WIRE 16 -1 (3650 3875)(3900 3875);
WIRE 16 -1 (3900 3925)(3900 3875);
WIRE 16 -1 (3900 3825)(3900 3750);
WIRE 16 -1 (3650 3825)(3900 3825);
WIRE 16 -1 (3650 3925)(3900 3925);
WIRE 16 -1 (3900 3975)(3900 3925);
WIRE 16 -1 (3650 3975)(3900 3975);
WIRE 16 -1 (1450 2700)(1450 2825);
WIRE 16 -1 (1800 2825)(1450 2825);
WIRE 16 -1 (1450 2975)(1450 2825);
WIRE 16 -1 (2700 2825)(1800 2825);
WIRE 16 -1 (1800 2725)(1800 2825);
WIRE 16 -1 (2700 2250)(2700 2825);
WIRE 16 -1 (2775 2250)(2700 2250);
WIRE 16 -1 (1625 5525)(1625 5650);
WIRE 16 -1 (1975 5650)(1625 5650);
WIRE 16 -1 (1625 5800)(1625 5650);
WIRE 16 -1 (1975 5550)(1975 5650);
WIRE 16 -1 (2300 5650)(1975 5650);
WIRE 16 -1 (2300 5075)(2300 5650);
WIRE 16 -1 (2800 5075)(2300 5075);
WIRE 16 -1 (6950 1200)(6950 1350);
WIRE 16 -1 (6525 1350)(6950 1350);
WIRE 16 -1 (3875 1050)(3875 1000);
WIRE 16 -1 (3875 1100)(3875 1050);
WIRE 16 -1 (3625 1050)(3875 1050);
WIRE 16 -1 (3875 1000)(3875 925);
WIRE 16 -1 (3625 1000)(3875 1000);
WIRE 16 -1 (3625 1100)(3875 1100);
WIRE 16 -1 (3875 1150)(3875 1100);
WIRE 16 -1 (3625 1150)(3875 1150);
WIRE 16 -1 (3625 1700)(5200 1700);
FORCEPROP 2 LAST SIG_NAME SW_PVDDCR_CPU1_P0_BOOTR4
J 0
(3815 1710);
DISPLAY 0.489362 (3815 1710);
FORCEPROP 2 LASTPROP $XRERR UNIQUE?
J 0
(3575 1710);
DISPLAY 0.638298 (3575 1710);
PAINT MONO (3575 1710);
DISPLAY INVISIBLE (3575 1710);
WIRE 16 -1 (5200 1700)(5200 1725);
WIRE 16 -1 (3625 1600)(4625 1600);
FORCEPROP 2 LAST SIG_NAME SW_PVDDCR_CPU1_P0_SW4
J 0
(3815 1610);
DISPLAY 0.489362 (3815 1610);
FORCEPROP 2 LASTPROP $XRERR UNIQUE?
J 0
(3575 1610);
DISPLAY 0.638298 (3575 1610);
PAINT MONO (3575 1610);
DISPLAY INVISIBLE (3575 1610);
WIRE 16 -1 (4625 1600)(5725 1600);
WIRE 16 -1 (4625 1600)(4625 1525);
WIRE 16 -1 (3625 1350)(4400 1350);
FORCEPROP 2 LAST SIG_NAME PVDDCR_CPU1_P0_VOS4
J 0
(3740 1375);
DISPLAY 0.489362 (3740 1375);
FORCEPROP 2 LASTPROP $XRERR UNIQUE?
J 0
(3500 1375);
DISPLAY 0.638298 (3500 1375);
PAINT MONO (3500 1375);
DISPLAY INVISIBLE (3500 1375);
WIRE 16 -1 (4400 1350)(4400 600);
WIRE 16 -1 (4400 600)(5725 600);
WIRE 16 -1 (3625 1250)(4200 1250);
FORCEPROP 2 LAST SIG_NAME NC_PVDDCR_CPU1_P0_GL2_4
J 0
(3740 1260);
DISPLAY 0.489362 (3740 1260);
FORCEPROP 2 LASTPROP $XRERR UNIQUE?
J 0
(4230 1250);
DISPLAY 0.638298 (4230 1250);
PAINT MONO (4230 1250);
DISPLAY INVISIBLE (4230 1250);
WIRE 16 -1 (3625 1300)(4200 1300);
FORCEPROP 2 LAST SIG_NAME NC_PVDDCR_CPU1_P0_GL1_4
J 0
(3740 1310);
DISPLAY 0.489362 (3740 1310);
FORCEPROP 2 LASTPROP $XRERR UNIQUE?
J 0
(4230 1300);
DISPLAY 0.638298 (4230 1300);
PAINT MONO (4230 1300);
DISPLAY INVISIBLE (4230 1300);
WIRE 16 -1 (3625 1950)(4375 1950);
FORCEPROP 2 LAST SIG_NAME SW_PVDDCR_CPU1_P0_BOOT4
J 0
(3815 1960);
DISPLAY 0.489362 (3815 1960);
FORCEPROP 2 LASTPROP $XRERR UNIQUE?
J 0
(3575 1960);
DISPLAY 0.638298 (3575 1960);
PAINT MONO (3575 1960);
DISPLAY INVISIBLE (3575 1960);
WIRE 16 -1 (2775 1750)(2675 1750);
WIRE 16 -1 (2675 1750)(2675 1950);
WIRE 16 -1 (2775 1950)(2675 1950);
WIRE 16 -1 (2675 1950)(2025 1950);
FORCEPROP 2 LAST SIG_NAME PVDDCR_CPU1_P0_VCC4
J 0
(2140 1960);
DISPLAY 0.489362 (2140 1960);
FORCEPROP 2 LASTPROP $XRERR UNIQUE?
J 0
(1900 1960);
DISPLAY 0.638298 (1900 1960);
PAINT MONO (1900 1960);
DISPLAY INVISIBLE (1900 1960);
WIRE 16 -1 (2025 2225)(2025 1950);
WIRE 16 -1 (1450 2225)(2025 2225);
WIRE 16 -1 (1450 2500)(1450 2225);
WIRE 16 -1 (1450 2225)(1450 2150);
WIRE 16 -1 (2675 1425)(800 1425);
WIRE 16 -1 (2675 1500)(2675 1425);
FORCEPROP 0 LAST CDS_PHYS_NET_NAME PVCCIN_CPU0_VREF
J 0
(2675 1450);
PAINT MONO (2675 1450);
DISPLAY INVISIBLE (2675 1450);
WIRE 16 -1 (800 1425)(800 1325);
WIRE 16 -1 (1825 1500)(2675 1500);
FORCEPROP 2 LAST SIG_NAME PVDDCR_CPU1_P0_VCCS
J 0
(1940 1510);
DISPLAY 0.489362 (1940 1510);
WIRE 16 -1 (2675 1500)(2775 1500);
WIRE 16 -1 (1300 1300)(2775 1300);
FORCEPROP 2 LAST SIG_NAME PVDDCR_CPU1_P0_LSET4
J 0
(1940 1310);
DISPLAY 0.489362 (1940 1310);
FORCEPROP 2 LASTPROP $XRERR UNIQUE?
J 0
(1700 1310);
DISPLAY 0.638298 (1700 1310);
PAINT MONO (1700 1310);
DISPLAY INVISIBLE (1700 1310);
WIRE 16 -1 (1300 1300)(1300 1200);
WIRE 16 -1 (2800 3825)(1850 3825);
FORCEPROP 2 LAST SIG_NAME PVDDCR_CPU1_P0_PWM3
J 0
(1965 3835);
DISPLAY 0.489362 (1965 3835);
WIRE 16 -1 (2800 3925)(1850 3925);
FORCEPROP 2 LAST SIG_NAME PVDDCR_CPU1_P0_TEMP0
J 0
(1965 3935);
DISPLAY 0.489362 (1965 3935);
WIRE 16 -1 (2775 1100)(1825 1100);
FORCEPROP 2 LAST SIG_NAME PVDDCR_CPU1_P0_TEMP0
J 0
(1940 1110);
DISPLAY 0.489362 (1940 1110);
WIRE 16 -1 (2775 1000)(1825 1000);
FORCEPROP 2 LAST SIG_NAME PVDDCR_CPU1_P0_PWM4
J 0
(1940 1010);
DISPLAY 0.489362 (1940 1010);
WIRE 16 -1 (2775 1600)(1825 1600);
FORCEPROP 2 LAST SIG_NAME PVDDCR_CPU1_P0_IMON4
J 0
(1940 1610);
DISPLAY 0.489362 (1940 1610);
WIRE 16 -1 (2775 1350)(2400 1350);
FORCEPROP 2 LAST SIG_NAME NC_PVDDCR_CPU1_P0_DNC4
J 0
(2205 1360);
DISPLAY 0.489362 (2205 1360);
FORCEPROP 2 LASTPROP $XRERR UNIQUE?
J 0
(2160 1350);
DISPLAY 0.638298 (2160 1350);
PAINT MONO (2160 1350);
DISPLAY INVISIBLE (2160 1350);
WIRE 16 -1 (2800 4575)(2700 4575);
WIRE 16 -1 (2700 4575)(2700 4775);
WIRE 16 -1 (2700 4775)(2800 4775);
WIRE 16 -1 (2700 4775)(2075 4775);
FORCEPROP 2 LAST SIG_NAME PVDDCR_CPU1_P0_VCC3
J 0
(2165 4785);
DISPLAY 0.489362 (2165 4785);
FORCEPROP 2 LASTPROP $XRERR UNIQUE?
J 0
(1925 4785);
DISPLAY 0.638298 (1925 4785);
PAINT MONO (1925 4785);
DISPLAY INVISIBLE (1925 4785);
WIRE 16 -1 (2075 5075)(2075 4775);
WIRE 16 -1 (1625 5075)(2075 5075);
WIRE 16 -1 (1625 5325)(1625 5075);
WIRE 16 -1 (1625 4975)(1625 5075);
WIRE 16 -1 (1325 4125)(2800 4125);
FORCEPROP 2 LAST SIG_NAME PVDDCR_CPU1_P0_LSET3
J 0
(1965 4135);
DISPLAY 0.489362 (1965 4135);
FORCEPROP 2 LASTPROP $XRERR UNIQUE?
J 0
(1725 4135);
DISPLAY 0.638298 (1725 4135);
PAINT MONO (1725 4135);
DISPLAY INVISIBLE (1725 4135);
WIRE 16 -1 (1325 4125)(1325 4025);
WIRE 16 -1 (2700 4250)(825 4250);
WIRE 16 -1 (2700 4325)(2700 4250);
FORCEPROP 0 LAST CDS_PHYS_NET_NAME PVCCIN_CPU0_VREF
J 0
(2700 4275);
PAINT MONO (2700 4275);
DISPLAY INVISIBLE (2700 4275);
WIRE 16 -1 (825 4250)(825 4150);
WIRE 16 -1 (1850 4325)(2700 4325);
FORCEPROP 2 LAST SIG_NAME PVDDCR_CPU1_P0_VCCS
J 0
(1965 4335);
DISPLAY 0.489362 (1965 4335);
WIRE 16 -1 (2700 4325)(2800 4325);
WIRE 16 -1 (2800 4425)(1850 4425);
FORCEPROP 2 LAST SIG_NAME PVDDCR_CPU1_P0_IMON3
J 0
(1965 4435);
DISPLAY 0.489362 (1965 4435);
WIRE 16 -1 (2800 4175)(2425 4175);
FORCEPROP 2 LAST SIG_NAME NC_PVDDCR_CPU1_P0_DNC3
J 0
(2230 4185);
DISPLAY 0.489362 (2230 4185);
FORCEPROP 2 LASTPROP $XRERR UNIQUE?
J 0
(2185 4175);
DISPLAY 0.638298 (2185 4175);
PAINT MONO (2185 4175);
DISPLAY INVISIBLE (2185 4175);
WIRE 16 -1 (4175 4125)(3650 4125);
FORCEPROP 2 LAST SIG_NAME NC_PVDDCR_CPU1_P0_GL1_3
J 0
(3740 4135);
DISPLAY 0.489362 (3740 4135);
FORCEPROP 2 LASTPROP $XRERR UNIQUE?
J 0
(4205 4125);
DISPLAY 0.638298 (4205 4125);
PAINT MONO (4205 4125);
DISPLAY INVISIBLE (4205 4125);
WIRE 16 -1 (4175 4075)(3650 4075);
FORCEPROP 2 LAST SIG_NAME NC_PVDDCR_CPU1_P0_GL2_3
J 0
(3740 4085);
DISPLAY 0.489362 (3740 4085);
FORCEPROP 2 LASTPROP $XRERR UNIQUE?
J 0
(4205 4075);
DISPLAY 0.638298 (4205 4075);
PAINT MONO (4205 4075);
DISPLAY INVISIBLE (4205 4075);
WIRE 16 -1 (4625 1325)(4625 1000);
FORCEPROP 2 LAST SIG_NAME SW_PVDDCR_CPU1_P0_SW4_RC
J 0
(4665 1110);
DISPLAY 0.489362 (4665 1110);
FORCEPROP 2 LASTPROP $XRERR UNIQUE?
J 0
(4425 1110);
DISPLAY 0.638298 (4425 1110);
PAINT MONO (4425 1110);
DISPLAY INVISIBLE (4425 1110);
WIRE 16 -1 (5250 1350)(5725 1350);
FORCEPROP 2 LAST SIG_NAME IND_CPU1_P0_CPL3
J 0
(5315 1360);
DISPLAY 0.489362 (5315 1360);
WIRE 16 -1 (4675 4125)(4675 3775);
FORCEPROP 2 LAST SIG_NAME SW_PVDDCR_CPU1_P0_SW3_RC
J 0
(4715 3935);
DISPLAY 0.489362 (4715 3935);
FORCEPROP 2 LASTPROP $XRERR UNIQUE?
J 0
(4475 3935);
DISPLAY 0.638298 (4475 3935);
PAINT MONO (4475 3935);
DISPLAY INVISIBLE (4475 3935);
WIRE 16 -1 (4425 4175)(4425 3325);
WIRE 16 -1 (3650 4175)(4425 4175);
FORCEPROP 2 LAST SIG_NAME PVDDCR_CPU1_P0_VOS3
J 0
(3740 4200);
DISPLAY 0.489362 (3740 4200);
FORCEPROP 2 LASTPROP $XRERR UNIQUE?
J 0
(3500 4200);
DISPLAY 0.638298 (3500 4200);
PAINT MONO (3500 4200);
DISPLAY INVISIBLE (3500 4200);
WIRE 16 -1 (4425 3325)(5725 3325);
WIRE 16 -1 (5275 4175)(6050 4175);
FORCEPROP 2 LAST SIG_NAME IND_CPU1_P0_CPL2
J 0
(5340 4185);
DISPLAY 0.489362 (5340 4185);
WIRE 16 -1 (6850 4175)(7350 4175);
FORCEPROP 2 LAST SIG_NAME IND_CPU1_P0_CPL3
J 0
(6940 4185);
DISPLAY 0.489362 (6940 4185);
DOT 1 (5600 2250);
DOT 1 (3875 1100);
DOT 1 (3875 1050);
DOT 1 (4425 2750);
DOT 1 (4025 2750);
DOT 1 (4625 1600);
DOT 1 (2675 1950);
DOT 1 (3900 3825);
DOT 1 (1450 2225);
DOT 1 (2675 1500);
DOT 1 (3875 1000);
DOT 1 (3900 3875);
DOT 1 (3900 3925);
DOT 1 (4075 5600);
DOT 1 (4825 2750);
DOT 1 (5225 2250);
DOT 1 (7225 1600);
DOT 1 (7475 1600);
DOT 1 (7900 1175);
DOT 1 (7900 1600);
DOT 1 (4875 5100);
DOT 1 (4475 5600);
DOT 1 (4875 5600);
DOT 1 (5650 5100);
DOT 1 (5275 5600);
DOT 1 (5650 5600);
DOT 1 (8350 4425);
DOT 1 (7925 4425);
DOT 1 (8350 4000);
DOT 1 (7700 4425);
DOT 1 (4475 5100);
DOT 1 (3825 5075);
DOT 1 (2700 4775);
DOT 1 (1625 5075);
DOT 1 (5275 5100);
DOT 1 (2700 4325);
DOT 1 (1625 5650);
DOT 1 (1450 2825);
DOT 1 (1800 2825);
DOT 1 (5600 2750);
DOT 1 (5225 2750);
DOT 1 (4675 4425);
DOT 1 (1975 5650);
DOT 1 (3800 2250);
DOT 1 (4425 2250);
DOT 1 (4825 2250);
FORCENOTE
PVDDCR_CPU1_P0_PHASE4
(2800 2925) 0;
DISPLAY LEFT (2800 2925);
DISPLAY 1.021277 (2800 2925);
PAINT WHITE (2800 2925);
FORCENOTE
2ND=CV+15^0TZ01
(6550 1675) 0;
DISPLAY LEFT (6550 1675);
DISPLAY 0.638298 (6550 1675);
PAINT WHITE (6550 1675);
FORCENOTE
DCR=2-3,0.27M OHM
(6550 1725) 0;
DISPLAY LEFT (6550 1725);
DISPLAY 0.638298 (6550 1725);
PAINT WHITE (6550 1725);
FORCENOTE
DCR=1-4,0.105M OHM
(6550 1775) 0;
DISPLAY LEFT (6550 1775);
DISPLAY 0.638298 (6550 1775);
PAINT WHITE (6550 1775);
FORCENOTE
ISAT:70A@100C
(6550 1875) 0;
DISPLAY LEFT (6550 1875);
DISPLAY 0.638298 (6550 1875);
PAINT WHITE (6550 1875);
FORCENOTE
PGL6303.151HLT
(6550 1925) 0;
DISPLAY LEFT (6550 1925);
DISPLAY 0.638298 (6550 1925);
PAINT WHITE (6550 1925);
FORCENOTE
11.0*7.5*12.5
(6550 1825) 0;
DISPLAY LEFT (6550 1825);
DISPLAY 0.638298 (6550 1825);
PAINT WHITE (6550 1825);
FORCENOTE
2ND=CV+15^0TZ01
(6875 4500) 0;
DISPLAY LEFT (6875 4500);
DISPLAY 0.638298 (6875 4500);
PAINT WHITE (6875 4500);
FORCENOTE
ISAT:70A@100C
(6875 4700) 0;
DISPLAY LEFT (6875 4700);
DISPLAY 0.638298 (6875 4700);
PAINT WHITE (6875 4700);
FORCENOTE
11.0*7.5*12.5
(6875 4650) 0;
DISPLAY LEFT (6875 4650);
DISPLAY 0.638298 (6875 4650);
PAINT WHITE (6875 4650);
FORCENOTE
DCR=1-4,0.105M OHM
(6875 4600) 0;
DISPLAY LEFT (6875 4600);
DISPLAY 0.638298 (6875 4600);
PAINT WHITE (6875 4600);
FORCENOTE
DCR=2-3,0.27M OHM
(6875 4550) 0;
DISPLAY LEFT (6875 4550);
DISPLAY 0.638298 (6875 4550);
PAINT WHITE (6875 4550);
FORCENOTE
PGL6303.151HLT
(6875 4750) 0;
DISPLAY LEFT (6875 4750);
DISPLAY 0.638298 (6875 4750);
PAINT WHITE (6875 4750);
FORCENOTE
PVDDCR_CPU1_P0_PHASE3
(2775 5800) 0;
DISPLAY LEFT (2775 5800);
DISPLAY 1.021277 (2775 5800);
PAINT WHITE (2775 5800);
QUIT
